FILE_TYPE = MACRO_DRAWING;
SET COLOR_WIRE YELLOW;
SET COLOR_PROP MONO;
SET COLOR_DOT WHITE;
SET COLOR_ARC YELLOW;
SET COLOR_BODY GREEN;
SET COLOR_NOTE MONO;
SET PROP_DISPLAY VALUE;
SET PAGE_NUMBER P217;
FORCEADD PVDDQ_ABC..1
(2900 2000);
FORCEPROP 3 LASTPIN (2900 1950) SIG_NAME PVDDQ_ABC\g
J 0
(2910 1960);
DISPLAY 0.659574 (2910 1960);
PAINT MONO (2910 1960);
DISPLAY INVISIBLE (2910 1960);
FORCEPROP 2 LAST CDS_LIB mstr_symbols
J 0
(2900 2000);
PAINT ORANGE (2900 2000);
DISPLAY INVISIBLE (2900 2000);
FORCEPROP 1 LAST BODY_TYPE PLUMBING
J 0
(2855 1957);
DISPLAY 0.340426 (2855 1957);
PAINT GREEN (2855 1957);
DISPLAY INVISIBLE (2855 1957);
FORCEPROP 1 LAST VOLTAGE 1.2V
J 0
(2855 1957);
DISPLAY 0.340426 (2855 1957);
PAINT SKYBLUE (2855 1957);
DISPLAY INVISIBLE (2855 1957);
FORCEPROP 1 LAST PATH I109
J 0
(2950 2025);
DISPLAY 0.872340 (2950 2025);
PAINT AQUA (2950 2025);
DISPLAY INVISIBLE (2950 2025);
FORCEPROP 1 LAST HDL_POWER PVDDQ_ABC
J 1
(2900 2050);
DISPLAY 0.872340 (2900 2050);
PAINT GREEN (2900 2050);
DISPLAY INVISIBLE (2900 2050);
FORCEADD CAP..1
(2875 2850);
FORCEPROP 1 LASTPIN (2875 2750) $PN 2
J 0
(2885 2730);
DISPLAY 0.617021 (2885 2730);
PAINT ORANGE (2885 2730);
FORCEPROP 1 LAST MATERIAL X5R
J 0
(2925 2750);
DISPLAY 0.617021 (2925 2750);
PAINT SKYBLUE (2925 2750);
FORCEPROP 1 LAST PACK_TYPE 0805
J 0
(2925 2650);
DISPLAY 0.617021 (2925 2650);
PAINT SKYBLUE (2925 2650);
FORCEPROP 1 LAST TOLERANCE 20%
J 0
(2925 2800);
DISPLAY 0.617021 (2925 2800);
PAINT SKYBLUE (2925 2800);
FORCEPROP 1 LASTPIN (2875 2950) $PN 1
J 0
(2885 2930);
DISPLAY 0.617021 (2885 2930);
PAINT ORANGE (2885 2930);
FORCEPROP 1 LAST LOCATION C5G20
J 0
(2925 2950);
DISPLAY 0.617021 (2925 2950);
PAINT AQUA (2925 2950);
FORCEPROP 1 LAST VALUE 100UF
J 0
(2925 2900);
DISPLAY 0.617021 (2925 2900);
PAINT SKYBLUE (2925 2900);
FORCEPROP 1 LAST VOLTAGE 4V
J 0
(2925 2850);
DISPLAY 0.617021 (2925 2850);
PAINT SKYBLUE (2925 2850);
FORCEPROP 1 LAST PART_NUMBER 602433-112
J 0
(2925 2700);
DISPLAY 0.617021 (2925 2700);
PAINT BLUE (2925 2700);
FORCEPROP 2 LAST CDS_LIB mstr_discrete
J 0
(2875 2850);
PAINT MONO (2875 2850);
DISPLAY INVISIBLE (2875 2850);
FORCEPROP 2 LAST BOM_COST MEM_VRD_PVDDQ_CD
J 0
(2925 3000);
PAINT MONO (2925 3000);
DISPLAY INVISIBLE (2925 3000);
FORCEPROP 2 LAST CDS_LOCATION C5G20
J 0
(2925 2950);
DISPLAY 0.617021 (2925 2950);
PAINT AQUA (2925 2950);
DISPLAY INVISIBLE (2925 2950);
FORCEPROP 1 LAST PATH I110
J 0
(2925 3000);
DISPLAY 0.978723 (2925 3000);
PAINT WHITE (2925 3000);
DISPLAY INVISIBLE (2925 3000);
FORCEPROP 2 LAST ROOM VDDQ_ABC_PWR_VR
J 0
(2925 3000);
PAINT MONO (2925 3000);
DISPLAY INVISIBLE (2925 3000);
FORCEPROP 2 LAST SEC_TYPE 0805
J 0
(2925 3050);
DISPLAY 1.021277 (2925 3050);
PAINT ORANGE (2925 3050);
DISPLAY INVISIBLE (2925 3050);
FORCEPROP 2 LAST SEC 1
J 0
(2925 3050);
DISPLAY 0.680851 (2925 3050);
PAINT MONO (2925 3050);
DISPLAY INVISIBLE (2925 3050);
FORCEADD GND..1
(4625 1350);
FORCEPROP 3 LASTPIN (4625 1400) SIG_NAME GND\g
J 0
(4635 1410);
DISPLAY 0.659574 (4635 1410);
PAINT MONO (4635 1410);
DISPLAY INVISIBLE (4635 1410);
FORCEPROP 2 LAST ROOM VDDQ_ABC_PWR_VR
J 0
(4075 1425);
PAINT ORANGE (4075 1425);
DISPLAY INVISIBLE (4075 1425);
FORCEPROP 2 LAST BOM_COST MEM_VRD_PVDDQ_CD
J 0
(4300 1425);
PAINT MONO (4300 1425);
DISPLAY INVISIBLE (4300 1425);
FORCEPROP 1 LAST BODY_TYPE PLUMBING
J 0
(4580 1307);
DISPLAY 0.340426 (4580 1307);
PAINT GREEN (4580 1307);
DISPLAY INVISIBLE (4580 1307);
FORCEPROP 1 LAST SIZE 1B
J 0
(4700 1300);
DISPLAY 0.893617 (4700 1300);
PAINT GREEN (4700 1300);
DISPLAY INVISIBLE (4700 1300);
FORCEPROP 2 LAST CDS_LIB mstr_symbols
J 0
(4625 1350);
PAINT ORANGE (4625 1350);
DISPLAY INVISIBLE (4625 1350);
FORCEPROP 1 LAST PATH I114
J 0
(4700 1350);
DISPLAY 1.170213 (4700 1350);
PAINT AQUA (4700 1350);
DISPLAY INVISIBLE (4700 1350);
FORCEPROP 1 LAST VOLTAGE 0
J 0
(4625 1350);
PAINT SKYBLUE (4625 1350);
DISPLAY INVISIBLE (4625 1350);
FORCEPROP 1 LAST HDL_POWER GND
J 0
(4625 1500);
DISPLAY 0.893617 (4625 1500);
PAINT GREEN (4625 1500);
DISPLAY INVISIBLE (4625 1500);
FORCEADD VCC_CORE..1
(200 1150);
FORCEPROP 3 LASTPIN (200 1100) SIG_NAME VR_FET_SW_P12V_STBY_PVDDQ_ABC\g
J 0
(210 1110);
DISPLAY 0.659574 (210 1110);
PAINT MONO (210 1110);
DISPLAY INVISIBLE (210 1110);
FORCEPROP 1 LAST HDL_POWER VR_FET_SW_P12V_STBY_PVDDQ_ABC
J 1
(200 1200);
DISPLAY 0.617021 (200 1200);
PAINT GREEN (200 1200);
FORCEPROP 2 LAST CDS_LIB mstr_symbols
J 0
(200 1150);
PAINT ORANGE (200 1150);
DISPLAY INVISIBLE (200 1150);
FORCEPROP 1 LAST PATH I120
J 0
(250 1175);
DISPLAY 1.170213 (250 1175);
PAINT AQUA (250 1175);
DISPLAY INVISIBLE (250 1175);
FORCEADD GND..1
(200 475);
FORCEPROP 3 LASTPIN (200 525) SIG_NAME GND\g
J 0
(210 535);
DISPLAY 0.659574 (210 535);
PAINT MONO (210 535);
DISPLAY INVISIBLE (210 535);
FORCEPROP 2 LAST ROOM VDDQ_ABC_PWR_VR
J 0
(-350 550);
PAINT ORANGE (-350 550);
DISPLAY INVISIBLE (-350 550);
FORCEPROP 2 LAST BOM_COST MEM_VRD_PVDDQ_CD
J 0
(-125 550);
PAINT MONO (-125 550);
DISPLAY INVISIBLE (-125 550);
FORCEPROP 1 LAST BODY_TYPE PLUMBING
J 0
(155 432);
DISPLAY 0.340426 (155 432);
PAINT GREEN (155 432);
DISPLAY INVISIBLE (155 432);
FORCEPROP 1 LAST SIZE 1B
J 0
(275 425);
DISPLAY 0.893617 (275 425);
PAINT GREEN (275 425);
DISPLAY INVISIBLE (275 425);
FORCEPROP 2 LAST CDS_LIB mstr_symbols
J 0
(200 475);
PAINT ORANGE (200 475);
DISPLAY INVISIBLE (200 475);
FORCEPROP 1 LAST PATH I123
J 0
(275 475);
DISPLAY 1.170213 (275 475);
PAINT AQUA (275 475);
DISPLAY INVISIBLE (275 475);
FORCEPROP 1 LAST VOLTAGE 0
J 0
(200 475);
PAINT SKYBLUE (200 475);
DISPLAY INVISIBLE (200 475);
FORCEPROP 1 LAST HDL_POWER GND
J 0
(200 625);
DISPLAY 0.893617 (200 625);
PAINT GREEN (200 625);
DISPLAY INVISIBLE (200 625);
FORCEADD INDUCTOR..1
(-225 900);
FORCEPROP 1 LASTPIN (-325 900) $PN 1
J 0
(-325 910);
DISPLAY 0.617021 (-325 910);
PAINT WHITE (-325 910);
FORCEPROP 1 LAST VALUE 100NH
J 2
(-230 815);
DISPLAY 0.617021 (-230 815);
PAINT SKYBLUE (-230 815);
FORCEPROP 1 LAST LOCATION L7F2
J 0
(-325 950);
DISPLAY 0.617021 (-325 950);
PAINT AQUA (-325 950);
FORCEPROP 1 LASTPIN (-125 900) $PN 2
J 2
(-115 910);
DISPLAY 0.617021 (-115 910);
PAINT WHITE (-115 910);
FORCEPROP 1 LAST MATERIAL IND
J 0
(-210 815);
DISPLAY 0.617021 (-210 815);
PAINT SKYBLUE (-210 815);
FORCEPROP 1 LAST PART_NUMBER D92183-020
J 0
(-325 1000);
DISPLAY 0.617021 (-325 1000);
PAINT BLUE (-325 1000);
FORCEPROP 1 LAST PACK_TYPE SM
J 0
(65 815);
DISPLAY 0.617021 (65 815);
PAINT SKYBLUE (65 815);
FORCEPROP 2 LAST CDS_LOCATION L7F2
J 0
(-325 950);
DISPLAY 0.617021 (-325 950);
PAINT AQUA (-325 950);
DISPLAY INVISIBLE (-325 950);
FORCEPROP 2 LAST CDS_LIB mstr_discrete
J 0
(-225 900);
PAINT ORANGE (-225 900);
DISPLAY INVISIBLE (-225 900);
FORCEPROP 2 LAST ROOM VDDQ_ABC_PWR_VR
J 0
(-325 1050);
PAINT MONO (-325 1050);
DISPLAY INVISIBLE (-325 1050);
FORCEPROP 1 LAST PATH I124
J 0
(-325 1050);
DISPLAY 1.319149 (-325 1050);
PAINT ORANGE (-325 1050);
DISPLAY INVISIBLE (-325 1050);
FORCEPROP 2 LAST SEC 1
J 0
(-320 1120);
DISPLAY 0.680851 (-320 1120);
PAINT MONO (-320 1120);
DISPLAY INVISIBLE (-320 1120);
FORCEPROP 2 LAST SEC_TYPE SM
J 0
(-325 1125);
DISPLAY 1.021277 (-325 1125);
PAINT ORANGE (-325 1125);
DISPLAY INVISIBLE (-325 1125);
FORCEPROP 2 LAST BOM_COST MEM_VRD_PVDDQ_CD
J 0
(-325 1050);
PAINT MONO (-325 1050);
DISPLAY INVISIBLE (-325 1050);
FORCEADD CAPP..1
(200 700);
FORCEPROP 1 LASTPIN (200 600) $PN 2
J 0
(210 585);
DISPLAY 0.617021 (210 585);
PAINT ORANGE (210 585);
FORCEPROP 1 LASTPIN (200 800) $PN 1
J 0
(210 785);
DISPLAY 0.617021 (210 785);
PAINT ORANGE (210 785);
FORCEPROP 1 LAST MATERIAL OSCON
J 0
(250 600);
DISPLAY 0.617021 (250 600);
PAINT SKYBLUE (250 600);
FORCEPROP 1 LAST VOLTAGE 16V
J 0
(250 650);
DISPLAY 0.617021 (250 650);
PAINT SKYBLUE (250 650);
FORCEPROP 1 LAST PACK_TYPE 2626
J 0
(250 550);
DISPLAY 0.617021 (250 550);
PAINT SKYBLUE (250 550);
FORCEPROP 1 LAST TOLERANCE 20%
J 0
(250 700);
DISPLAY 0.617021 (250 700);
PAINT SKYBLUE (250 700);
FORCEPROP 1 LAST VALUE 270UF
J 0
(250 750);
DISPLAY 0.617021 (250 750);
PAINT SKYBLUE (250 750);
FORCEPROP 1 LAST LOCATION C7G2
J 0
(250 800);
DISPLAY 0.617021 (250 800);
PAINT AQUA (250 800);
FORCEPROP 1 LAST PART_NUMBER A31228-047
J 0
(250 500);
DISPLAY 0.617021 (250 500);
PAINT BLUE (250 500);
FORCEPROP 2 LAST CDS_LIB mstr_discrete
J 0
(200 700);
PAINT ORANGE (200 700);
DISPLAY INVISIBLE (200 700);
FORCEPROP 2 LAST CDS_LOCATION C7G2
J 0
(250 800);
DISPLAY 0.617021 (250 800);
PAINT AQUA (250 800);
DISPLAY INVISIBLE (250 800);
FORCEPROP 1 LAST PATH I175
J 0
(250 850);
DISPLAY 1.319149 (250 850);
PAINT ORANGE (250 850);
DISPLAY INVISIBLE (250 850);
FORCEPROP 2 LAST ROOM VDDQ_ABC_PWR_VR
J 0
(250 850);
DISPLAY 1.361702 (250 850);
PAINT ORANGE (250 850);
DISPLAY INVISIBLE (250 850);
FORCEPROP 2 LAST SEC 1
J 0
(250 925);
DISPLAY 0.680851 (250 925);
PAINT MONO (250 925);
DISPLAY INVISIBLE (250 925);
FORCEPROP 2 LAST SEC_TYPE 2626
J 0
(250 925);
DISPLAY 1.021277 (250 925);
PAINT ORANGE (250 925);
DISPLAY INVISIBLE (250 925);
FORCEADD P12V_STBY..1
(-550 1150);
FORCEPROP 3 LASTPIN (-550 1100) SIG_NAME P12V_STBY\g
J 0
(-540 1110);
DISPLAY 0.659574 (-540 1110);
PAINT MONO (-540 1110);
DISPLAY INVISIBLE (-540 1110);
FORCEPROP 1 LAST VOLTAGE 12.0V
J 0
(-595 1107);
DISPLAY 0.340426 (-595 1107);
PAINT SKYBLUE (-595 1107);
DISPLAY INVISIBLE (-595 1107);
FORCEPROP 1 LAST HDL_POWER P12V_STBY
J 0
(-850 1025);
DISPLAY 0.872340 (-850 1025);
PAINT ORANGE (-850 1025);
DISPLAY INVISIBLE (-850 1025);
FORCEPROP 1 LAST BODY_TYPE PLUMBING
J 0
(-595 1107);
DISPLAY 0.340426 (-595 1107);
PAINT GREEN (-595 1107);
DISPLAY INVISIBLE (-595 1107);
FORCEPROP 2 LAST CDS_LIB mstr_symbols
J 0
(-550 1150);
PAINT ORANGE (-550 1150);
DISPLAY INVISIBLE (-550 1150);
FORCEPROP 1 LAST PATH I183
J 0
(-505 1152);
DISPLAY 0.340426 (-505 1152);
PAINT GREEN (-505 1152);
DISPLAY INVISIBLE (-505 1152);
FORCEPROP 1 LAST SIZE 1B
J 0
(-505 1172);
DISPLAY 0.340426 (-505 1172);
PAINT GREEN (-505 1172);
DISPLAY INVISIBLE (-505 1172);
FORCEADD CAP..1
(-1650 2850);
FORCEPROP 1 LASTPIN (-1650 2750) $PN 2
J 0
(-1640 2730);
DISPLAY 0.617021 (-1640 2730);
PAINT ORANGE (-1640 2730);
FORCEPROP 1 LASTPIN (-1650 2950) $PN 1
J 0
(-1640 2930);
DISPLAY 0.617021 (-1640 2930);
PAINT ORANGE (-1640 2930);
FORCEPROP 1 LAST MATERIAL X6S
J 0
(-1600 2750);
DISPLAY 0.617021 (-1600 2750);
PAINT SKYBLUE (-1600 2750);
FORCEPROP 1 LAST PACK_TYPE 0805LF
J 0
(-1600 2650);
DISPLAY 0.617021 (-1600 2650);
PAINT SKYBLUE (-1600 2650);
FORCEPROP 1 LAST TOLERANCE 20%
J 0
(-1600 2800);
DISPLAY 0.617021 (-1600 2800);
PAINT SKYBLUE (-1600 2800);
FORCEPROP 1 LAST VALUE 22UF
J 0
(-1600 2900);
DISPLAY 0.617021 (-1600 2900);
PAINT SKYBLUE (-1600 2900);
FORCEPROP 1 LAST PART_NUMBER C95333-002
J 0
(-1600 2700);
DISPLAY 0.617021 (-1600 2700);
PAINT BLUE (-1600 2700);
FORCEPROP 1 LAST LOCATION C5P39
J 0
(-1600 2950);
DISPLAY 0.617021 (-1600 2950);
PAINT AQUA (-1600 2950);
FORCEPROP 2 LAST CDS_LIB mstr_discrete
J 0
(-1650 2850);
PAINT ORANGE (-1650 2850);
DISPLAY INVISIBLE (-1650 2850);
FORCEPROP 1 LAST VOLTAGE 4V
J 0
(-1600 2850);
PAINT SKYBLUE (-1600 2850);
DISPLAY INVISIBLE (-1600 2850);
FORCEPROP 2 LAST ROOM VDDQ_ABC_CPU0
J 0
(-1600 3000);
PAINT MONO (-1600 3000);
DISPLAY INVISIBLE (-1600 3000);
FORCEPROP 1 LAST PATH I184
J 0
(-1600 3000);
DISPLAY 0.978723 (-1600 3000);
PAINT WHITE (-1600 3000);
DISPLAY INVISIBLE (-1600 3000);
FORCEPROP 2 LAST CDS_LOCATION C5P39
J 0
(-1600 2950);
DISPLAY 0.617021 (-1600 2950);
PAINT AQUA (-1600 2950);
DISPLAY INVISIBLE (-1600 2950);
FORCEPROP 2 LAST BOM_COST MEM_VRD_PVDDQ_ABC
J 0
(-1600 3000);
PAINT MONO (-1600 3000);
DISPLAY INVISIBLE (-1600 3000);
FORCEPROP 2 LAST SEC_TYPE 0805LF
J 0
(-1600 3050);
DISPLAY 1.021277 (-1600 3050);
PAINT ORANGE (-1600 3050);
DISPLAY INVISIBLE (-1600 3050);
FORCEPROP 2 LAST SEC 1
J 0
(-1600 3050);
DISPLAY 0.680851 (-1600 3050);
PAINT MONO (-1600 3050);
DISPLAY INVISIBLE (-1600 3050);
FORCEADD CAP..1
(150 2825);
FORCEPROP 1 LASTPIN (150 2725) $PN 2
J 0
(160 2705);
DISPLAY 0.617021 (160 2705);
PAINT ORANGE (160 2705);
FORCEPROP 1 LASTPIN (150 2925) $PN 1
J 0
(160 2905);
DISPLAY 0.617021 (160 2905);
PAINT ORANGE (160 2905);
FORCEPROP 1 LAST VOLTAGE 4V
J 0
(200 2825);
DISPLAY 0.617021 (200 2825);
PAINT SKYBLUE (200 2825);
FORCEPROP 1 LAST MATERIAL X6S
J 0
(200 2725);
DISPLAY 0.617021 (200 2725);
PAINT SKYBLUE (200 2725);
FORCEPROP 1 LAST PACK_TYPE 0603LF
J 0
(200 2625);
DISPLAY 0.617021 (200 2625);
PAINT SKYBLUE (200 2625);
FORCEPROP 1 LAST TOLERANCE 20%
J 0
(200 2775);
DISPLAY 0.617021 (200 2775);
PAINT SKYBLUE (200 2775);
FORCEPROP 1 LAST VALUE 10UF
J 0
(200 2875);
DISPLAY 0.617021 (200 2875);
PAINT SKYBLUE (200 2875);
FORCEPROP 1 LAST PART_NUMBER E15431-001
J 0
(200 2675);
DISPLAY 0.617021 (200 2675);
PAINT BLUE (200 2675);
FORCEPROP 1 LAST LOCATION C5D57
J 0
(200 2925);
DISPLAY 0.617021 (200 2925);
PAINT AQUA (200 2925);
FORCEPROP 2 LAST ROOM VDDQ_ABC_CPU0
J 0
(200 2975);
PAINT MONO (200 2975);
DISPLAY INVISIBLE (200 2975);
FORCEPROP 1 LAST PATH I186
J 0
(200 2975);
DISPLAY 0.978723 (200 2975);
PAINT WHITE (200 2975);
DISPLAY INVISIBLE (200 2975);
FORCEPROP 2 LAST CDS_LOCATION C5D57
J 0
(200 2925);
DISPLAY 0.617021 (200 2925);
PAINT AQUA (200 2925);
DISPLAY INVISIBLE (200 2925);
FORCEPROP 2 LAST SEC 1
J 0
(200 3025);
DISPLAY 0.680851 (200 3025);
PAINT MONO (200 3025);
DISPLAY INVISIBLE (200 3025);
FORCEPROP 2 LAST BOM_COST MEM_VRD_PVDDQ_ABC
J 0
(200 2975);
PAINT MONO (200 2975);
DISPLAY INVISIBLE (200 2975);
FORCEPROP 2 LAST CDS_LIB mstr_discrete
J 0
(150 2825);
PAINT ORANGE (150 2825);
DISPLAY INVISIBLE (150 2825);
FORCEPROP 2 LAST SEC_TYPE 0603LF
J 0
(200 3025);
DISPLAY 1.021277 (200 3025);
PAINT ORANGE (200 3025);
DISPLAY INVISIBLE (200 3025);
FORCEADD GND..1
(150 2525);
FORCEPROP 3 LASTPIN (150 2575) SIG_NAME GND\g
J 0
(160 2585);
DISPLAY 0.659574 (160 2585);
PAINT MONO (160 2585);
DISPLAY INVISIBLE (160 2585);
FORCEPROP 2 LAST ROOM VDDQ_ABC_PWR_VR
J 0
(-400 2600);
PAINT ORANGE (-400 2600);
DISPLAY INVISIBLE (-400 2600);
FORCEPROP 2 LAST BOM_COST MEM_VRD_PVDDQ_CD
J 0
(-175 2600);
PAINT MONO (-175 2600);
DISPLAY INVISIBLE (-175 2600);
FORCEPROP 1 LAST SIZE 1B
J 0
(225 2475);
DISPLAY 0.893617 (225 2475);
PAINT GREEN (225 2475);
DISPLAY INVISIBLE (225 2475);
FORCEPROP 1 LAST BODY_TYPE PLUMBING
J 0
(105 2482);
DISPLAY 0.340426 (105 2482);
PAINT GREEN (105 2482);
DISPLAY INVISIBLE (105 2482);
FORCEPROP 2 LAST CDS_LIB mstr_symbols
J 0
(150 2525);
PAINT ORANGE (150 2525);
DISPLAY INVISIBLE (150 2525);
FORCEPROP 1 LAST PATH I187
J 0
(225 2525);
DISPLAY 0.872340 (225 2525);
PAINT AQUA (225 2525);
DISPLAY INVISIBLE (225 2525);
FORCEPROP 1 LAST VOLTAGE 0
J 0
(150 2525);
PAINT SKYBLUE (150 2525);
DISPLAY INVISIBLE (150 2525);
FORCEPROP 1 LAST HDL_POWER GND
J 0
(150 2675);
DISPLAY 0.893617 (150 2675);
PAINT GREEN (150 2675);
DISPLAY INVISIBLE (150 2675);
FORCEADD CAP..1
(-200 2850);
FORCEPROP 1 LAST MATERIAL X6S
J 0
(-150 2750);
DISPLAY 0.617021 (-150 2750);
PAINT SKYBLUE (-150 2750);
FORCEPROP 1 LASTPIN (-200 2750) $PN 2
J 0
(-190 2730);
DISPLAY 0.617021 (-190 2730);
PAINT ORANGE (-190 2730);
FORCEPROP 1 LAST TOLERANCE 20%
J 0
(-150 2800);
DISPLAY 0.617021 (-150 2800);
PAINT SKYBLUE (-150 2800);
FORCEPROP 1 LASTPIN (-200 2950) $PN 1
J 0
(-190 2930);
DISPLAY 0.617021 (-190 2930);
PAINT ORANGE (-190 2930);
FORCEPROP 1 LAST VOLTAGE 4V
J 0
(-150 2850);
DISPLAY 0.617021 (-150 2850);
PAINT SKYBLUE (-150 2850);
FORCEPROP 1 LAST VALUE 10UF
J 0
(-150 2900);
DISPLAY 0.617021 (-150 2900);
PAINT SKYBLUE (-150 2900);
FORCEPROP 1 LAST LOCATION C5D56
J 0
(-150 2950);
DISPLAY 0.617021 (-150 2950);
PAINT AQUA (-150 2950);
FORCEPROP 1 LAST PACK_TYPE 0603LF
J 0
(-150 2650);
DISPLAY 0.617021 (-150 2650);
PAINT SKYBLUE (-150 2650);
FORCEPROP 1 LAST PART_NUMBER E15431-001
J 0
(-150 2700);
DISPLAY 0.617021 (-150 2700);
PAINT BLUE (-150 2700);
FORCEPROP 2 LAST CDS_LIB mstr_discrete
J 0
(-200 2850);
PAINT ORANGE (-200 2850);
DISPLAY INVISIBLE (-200 2850);
FORCEPROP 2 LAST BOM_COST MEM_VRD_PVDDQ_ABC
J 0
(-150 3000);
PAINT MONO (-150 3000);
DISPLAY INVISIBLE (-150 3000);
FORCEPROP 2 LAST CDS_LOCATION C5D56
J 0
(-150 2950);
DISPLAY 0.617021 (-150 2950);
PAINT AQUA (-150 2950);
DISPLAY INVISIBLE (-150 2950);
FORCEPROP 1 LAST PATH I188
J 0
(-150 3000);
DISPLAY 0.978723 (-150 3000);
PAINT WHITE (-150 3000);
DISPLAY INVISIBLE (-150 3000);
FORCEPROP 2 LAST ROOM VDDQ_ABC_CPU0
J 0
(-150 3000);
PAINT MONO (-150 3000);
DISPLAY INVISIBLE (-150 3000);
FORCEPROP 2 LAST SEC_TYPE 0603LF
J 0
(-150 3050);
DISPLAY 1.021277 (-150 3050);
PAINT ORANGE (-150 3050);
DISPLAY INVISIBLE (-150 3050);
FORCEPROP 2 LAST SEC 1
J 0
(-150 3050);
DISPLAY 0.680851 (-150 3050);
PAINT MONO (-150 3050);
DISPLAY INVISIBLE (-150 3050);
FORCEADD CAP..1
(-550 2850);
FORCEPROP 1 LASTPIN (-550 2750) $PN 2
J 0
(-540 2730);
DISPLAY 0.617021 (-540 2730);
PAINT ORANGE (-540 2730);
FORCEPROP 1 LASTPIN (-550 2950) $PN 1
J 0
(-540 2930);
DISPLAY 0.617021 (-540 2930);
PAINT ORANGE (-540 2930);
FORCEPROP 1 LAST MATERIAL X6S
J 0
(-500 2750);
DISPLAY 0.617021 (-500 2750);
PAINT SKYBLUE (-500 2750);
FORCEPROP 1 LAST VOLTAGE 4V
J 0
(-500 2850);
DISPLAY 0.617021 (-500 2850);
PAINT SKYBLUE (-500 2850);
FORCEPROP 1 LAST PACK_TYPE 0603LF
J 0
(-500 2650);
DISPLAY 0.617021 (-500 2650);
PAINT SKYBLUE (-500 2650);
FORCEPROP 1 LAST TOLERANCE 20%
J 0
(-500 2800);
DISPLAY 0.617021 (-500 2800);
PAINT SKYBLUE (-500 2800);
FORCEPROP 1 LAST VALUE 10UF
J 0
(-500 2900);
DISPLAY 0.617021 (-500 2900);
PAINT SKYBLUE (-500 2900);
FORCEPROP 1 LAST LOCATION C5D55
J 0
(-500 2950);
DISPLAY 0.617021 (-500 2950);
PAINT AQUA (-500 2950);
FORCEPROP 1 LAST PART_NUMBER E15431-001
J 0
(-500 2700);
DISPLAY 0.617021 (-500 2700);
PAINT BLUE (-500 2700);
FORCEPROP 2 LAST CDS_LIB mstr_discrete
J 0
(-550 2850);
PAINT ORANGE (-550 2850);
DISPLAY INVISIBLE (-550 2850);
FORCEPROP 2 LAST BOM_COST MEM_VRD_PVDDQ_ABC
J 0
(-500 3000);
PAINT MONO (-500 3000);
DISPLAY INVISIBLE (-500 3000);
FORCEPROP 2 LAST CDS_LOCATION C5D55
J 0
(-500 2950);
DISPLAY 0.617021 (-500 2950);
PAINT AQUA (-500 2950);
DISPLAY INVISIBLE (-500 2950);
FORCEPROP 1 LAST PATH I189
J 0
(-500 3000);
DISPLAY 0.978723 (-500 3000);
PAINT WHITE (-500 3000);
DISPLAY INVISIBLE (-500 3000);
FORCEPROP 2 LAST ROOM VDDQ_ABC_CPU0
J 0
(-500 3000);
PAINT MONO (-500 3000);
DISPLAY INVISIBLE (-500 3000);
FORCEPROP 2 LAST SEC_TYPE 0603LF
J 0
(-500 3050);
DISPLAY 1.021277 (-500 3050);
PAINT ORANGE (-500 3050);
DISPLAY INVISIBLE (-500 3050);
FORCEPROP 2 LAST SEC 1
J 0
(-500 3050);
DISPLAY 0.680851 (-500 3050);
PAINT MONO (-500 3050);
DISPLAY INVISIBLE (-500 3050);
FORCEADD CAP..1
(-900 2850);
FORCEPROP 1 LASTPIN (-900 2750) $PN 2
J 0
(-890 2730);
DISPLAY 0.617021 (-890 2730);
PAINT ORANGE (-890 2730);
FORCEPROP 1 LASTPIN (-900 2950) $PN 1
J 0
(-890 2930);
DISPLAY 0.617021 (-890 2930);
PAINT ORANGE (-890 2930);
FORCEPROP 1 LAST VOLTAGE 4V
J 0
(-850 2850);
DISPLAY 0.617021 (-850 2850);
PAINT SKYBLUE (-850 2850);
FORCEPROP 1 LAST MATERIAL X6S
J 0
(-850 2750);
DISPLAY 0.617021 (-850 2750);
PAINT SKYBLUE (-850 2750);
FORCEPROP 1 LAST PACK_TYPE 0603LF
J 0
(-850 2650);
DISPLAY 0.617021 (-850 2650);
PAINT SKYBLUE (-850 2650);
FORCEPROP 1 LAST TOLERANCE 20%
J 0
(-850 2800);
DISPLAY 0.617021 (-850 2800);
PAINT SKYBLUE (-850 2800);
FORCEPROP 1 LAST VALUE 10UF
J 0
(-850 2900);
DISPLAY 0.617021 (-850 2900);
PAINT SKYBLUE (-850 2900);
FORCEPROP 1 LAST PART_NUMBER E15431-001
J 0
(-850 2700);
DISPLAY 0.617021 (-850 2700);
PAINT BLUE (-850 2700);
FORCEPROP 1 LAST LOCATION C5D54
J 0
(-850 2950);
DISPLAY 0.617021 (-850 2950);
PAINT AQUA (-850 2950);
FORCEPROP 2 LAST CDS_LIB mstr_discrete
J 0
(-900 2850);
PAINT ORANGE (-900 2850);
DISPLAY INVISIBLE (-900 2850);
FORCEPROP 2 LAST BOM_COST MEM_VRD_PVDDQ_ABC
J 0
(-850 3000);
PAINT MONO (-850 3000);
DISPLAY INVISIBLE (-850 3000);
FORCEPROP 2 LAST CDS_LOCATION C5D54
J 0
(-850 2950);
DISPLAY 0.617021 (-850 2950);
PAINT AQUA (-850 2950);
DISPLAY INVISIBLE (-850 2950);
FORCEPROP 1 LAST PATH I190
J 0
(-850 3000);
DISPLAY 0.978723 (-850 3000);
PAINT WHITE (-850 3000);
DISPLAY INVISIBLE (-850 3000);
FORCEPROP 2 LAST ROOM VDDQ_ABC_CPU0
J 0
(-850 3000);
PAINT MONO (-850 3000);
DISPLAY INVISIBLE (-850 3000);
FORCEPROP 2 LAST SEC_TYPE 0603LF
J 0
(-850 3050);
DISPLAY 1.021277 (-850 3050);
PAINT ORANGE (-850 3050);
DISPLAY INVISIBLE (-850 3050);
FORCEPROP 2 LAST SEC 1
J 0
(-850 3050);
DISPLAY 0.680851 (-850 3050);
PAINT MONO (-850 3050);
DISPLAY INVISIBLE (-850 3050);
FORCEADD PVDDQ_ABC..1
(-1650 3125);
FORCEPROP 3 LASTPIN (-1650 3075) SIG_NAME PVDDQ_ABC\g
J 0
(-1640 3085);
DISPLAY 0.659574 (-1640 3085);
PAINT MONO (-1640 3085);
DISPLAY INVISIBLE (-1640 3085);
FORCEPROP 1 LAST VOLTAGE 1.2V
J 0
(-1695 3082);
DISPLAY 0.340426 (-1695 3082);
PAINT SKYBLUE (-1695 3082);
DISPLAY INVISIBLE (-1695 3082);
FORCEPROP 1 LAST HDL_POWER PVDDQ_ABC
J 1
(-1650 3175);
DISPLAY 0.872340 (-1650 3175);
PAINT GREEN (-1650 3175);
DISPLAY INVISIBLE (-1650 3175);
FORCEPROP 1 LAST PATH I192
J 0
(-1600 3150);
DISPLAY 0.872340 (-1600 3150);
PAINT AQUA (-1600 3150);
DISPLAY INVISIBLE (-1600 3150);
FORCEPROP 1 LAST BODY_TYPE PLUMBING
J 0
(-1695 3082);
DISPLAY 0.340426 (-1695 3082);
PAINT GREEN (-1695 3082);
DISPLAY INVISIBLE (-1695 3082);
FORCEPROP 2 LAST CDS_LIB mstr_symbols
J 0
(-1650 3125);
PAINT ORANGE (-1650 3125);
DISPLAY INVISIBLE (-1650 3125);
FORCEPROP 2 LAST BOM_COST MEM_VRD_PVDDQ_CD
J 0
(-1575 3225);
PAINT MONO (-1575 3225);
DISPLAY INVISIBLE (-1575 3225);
FORCEPROP 2 LAST ROOM VDDQ_ABC_PWR_VR
J 0
(-1400 3225);
PAINT ORANGE (-1400 3225);
DISPLAY INVISIBLE (-1400 3225);
FORCEADD CAP..1
(-1300 2850);
FORCEPROP 1 LASTPIN (-1300 2750) $PN 2
J 0
(-1290 2730);
DISPLAY 0.617021 (-1290 2730);
PAINT ORANGE (-1290 2730);
FORCEPROP 1 LASTPIN (-1300 2950) $PN 1
J 0
(-1290 2930);
DISPLAY 0.617021 (-1290 2930);
PAINT ORANGE (-1290 2930);
FORCEPROP 1 LAST LOCATION C5P38
J 0
(-1250 2950);
DISPLAY 0.617021 (-1250 2950);
PAINT AQUA (-1250 2950);
FORCEPROP 1 LAST VALUE 22UF
J 0
(-1250 2900);
DISPLAY 0.617021 (-1250 2900);
PAINT SKYBLUE (-1250 2900);
FORCEPROP 1 LAST TOLERANCE 20%
J 0
(-1250 2800);
DISPLAY 0.617021 (-1250 2800);
PAINT SKYBLUE (-1250 2800);
FORCEPROP 1 LAST PACK_TYPE 0805LF
J 0
(-1250 2650);
DISPLAY 0.617021 (-1250 2650);
PAINT SKYBLUE (-1250 2650);
FORCEPROP 1 LAST MATERIAL X6S
J 0
(-1250 2750);
DISPLAY 0.617021 (-1250 2750);
PAINT SKYBLUE (-1250 2750);
FORCEPROP 1 LAST PART_NUMBER C95333-002
J 0
(-1250 2700);
DISPLAY 0.617021 (-1250 2700);
PAINT BLUE (-1250 2700);
FORCEPROP 2 LAST CDS_LIB mstr_discrete
J 0
(-1300 2850);
PAINT ORANGE (-1300 2850);
DISPLAY INVISIBLE (-1300 2850);
FORCEPROP 2 LAST BOM_COST MEM_VRD_PVDDQ_ABC
J 0
(-1250 3000);
PAINT MONO (-1250 3000);
DISPLAY INVISIBLE (-1250 3000);
FORCEPROP 2 LAST CDS_LOCATION C5P38
J 0
(-1250 2950);
DISPLAY 0.617021 (-1250 2950);
PAINT AQUA (-1250 2950);
DISPLAY INVISIBLE (-1250 2950);
FORCEPROP 1 LAST PATH I193
J 0
(-1250 3000);
DISPLAY 0.978723 (-1250 3000);
PAINT WHITE (-1250 3000);
DISPLAY INVISIBLE (-1250 3000);
FORCEPROP 2 LAST ROOM VDDQ_ABC_CPU0
J 0
(-1250 3000);
PAINT MONO (-1250 3000);
DISPLAY INVISIBLE (-1250 3000);
FORCEPROP 1 LAST VOLTAGE 4V
J 0
(-1250 2850);
PAINT SKYBLUE (-1250 2850);
DISPLAY INVISIBLE (-1250 2850);
FORCEPROP 2 LAST SEC_TYPE 0805LF
J 0
(-1250 3050);
DISPLAY 1.021277 (-1250 3050);
PAINT ORANGE (-1250 3050);
DISPLAY INVISIBLE (-1250 3050);
FORCEPROP 2 LAST SEC 1
J 0
(-1250 3050);
DISPLAY 0.680851 (-1250 3050);
PAINT MONO (-1250 3050);
DISPLAY INVISIBLE (-1250 3050);
FORCEADD PVDDQ_ABC..1
(2925 1275);
FORCEPROP 3 LASTPIN (2925 1225) SIG_NAME PVDDQ_ABC\g
J 0
(2935 1235);
DISPLAY 0.659574 (2935 1235);
PAINT MONO (2935 1235);
DISPLAY INVISIBLE (2935 1235);
FORCEPROP 1 LAST BODY_TYPE PLUMBING
J 0
(2880 1232);
DISPLAY 0.340426 (2880 1232);
PAINT GREEN (2880 1232);
DISPLAY INVISIBLE (2880 1232);
FORCEPROP 1 LAST VOLTAGE 1.2V
J 0
(2880 1232);
DISPLAY 0.340426 (2880 1232);
PAINT SKYBLUE (2880 1232);
DISPLAY INVISIBLE (2880 1232);
FORCEPROP 2 LAST CDS_LIB mstr_symbols
J 0
(2925 1275);
PAINT ORANGE (2925 1275);
DISPLAY INVISIBLE (2925 1275);
FORCEPROP 1 LAST PATH I201
J 0
(2975 1300);
DISPLAY 0.872340 (2975 1300);
PAINT AQUA (2975 1300);
DISPLAY INVISIBLE (2975 1300);
FORCEPROP 1 LAST HDL_POWER PVDDQ_ABC
J 1
(2925 1325);
DISPLAY 0.872340 (2925 1325);
PAINT GREEN (2925 1325);
DISPLAY INVISIBLE (2925 1325);
FORCEADD GND..1
(3575 625);
FORCEPROP 3 LASTPIN (3575 675) SIG_NAME GND\g
J 0
(3585 685);
DISPLAY 0.659574 (3585 685);
PAINT MONO (3585 685);
DISPLAY INVISIBLE (3585 685);
FORCEPROP 2 LAST BOM_COST MEM_VRD_PVDDQ_CD
J 0
(3250 700);
PAINT MONO (3250 700);
DISPLAY INVISIBLE (3250 700);
FORCEPROP 2 LAST CDS_LIB mstr_symbols
J 0
(3575 625);
PAINT ORANGE (3575 625);
DISPLAY INVISIBLE (3575 625);
FORCEPROP 1 LAST BODY_TYPE PLUMBING
J 0
(3530 582);
DISPLAY 0.340426 (3530 582);
PAINT GREEN (3530 582);
DISPLAY INVISIBLE (3530 582);
FORCEPROP 1 LAST HDL_POWER GND
J 0
(3575 775);
DISPLAY 0.893617 (3575 775);
PAINT GREEN (3575 775);
DISPLAY INVISIBLE (3575 775);
FORCEPROP 1 LAST VOLTAGE 0
J 0
(3575 625);
PAINT SKYBLUE (3575 625);
DISPLAY INVISIBLE (3575 625);
FORCEPROP 1 LAST SIZE 1B
J 0
(3650 575);
DISPLAY 0.893617 (3650 575);
PAINT GREEN (3650 575);
DISPLAY INVISIBLE (3650 575);
FORCEPROP 1 LAST PATH I203
J 0
(3650 625);
DISPLAY 0.872340 (3650 625);
PAINT AQUA (3650 625);
DISPLAY INVISIBLE (3650 625);
FORCEADD CAP_A..1
(2925 1000);
FORCEPROP 1 LAST TOLERANCE 20%
J 0
(2975 950);
DISPLAY 0.617021 (2975 950);
PAINT SKYBLUE (2975 950);
FORCEPROP 1 LAST MATERIAL X5R
J 0
(2975 900);
DISPLAY 0.617021 (2975 900);
PAINT SKYBLUE (2975 900);
FORCEPROP 1 LASTPIN (2925 900) $PN 2
J 0
(2935 880);
DISPLAY 0.617021 (2935 880);
PAINT ORANGE (2935 880);
FORCEPROP 1 LAST VOLTAGE 4V
J 0
(2975 1000);
DISPLAY 0.617021 (2975 1000);
PAINT SKYBLUE (2975 1000);
FORCEPROP 1 LASTPIN (2925 1100) $PN 1
J 0
(2935 1080);
DISPLAY 0.617021 (2935 1080);
PAINT ORANGE (2935 1080);
FORCEPROP 1 LAST PACK_TYPE 0603V
J 0
(2975 800);
DISPLAY 0.617021 (2975 800);
PAINT SKYBLUE (2975 800);
FORCEPROP 1 LAST VALUE 47UF
J 0
(2975 1050);
DISPLAY 0.617021 (2975 1050);
PAINT SKYBLUE (2975 1050);
FORCEPROP 1 LAST PART_NUMBER 602433-106
J 0
(2975 850);
DISPLAY 0.617021 (2975 850);
PAINT BLUE (2975 850);
FORCEPROP 1 LAST LOCATION C5F2
J 0
(2975 1100);
DISPLAY 0.617021 (2975 1100);
PAINT AQUA (2975 1100);
FORCEPROP 2 LAST CDS_LIB dev_discrete
J 0
(2925 1000);
PAINT ORANGE (2925 1000);
DISPLAY INVISIBLE (2925 1000);
FORCEPROP 1 LAST PATH I205
J 0
(2975 1150);
DISPLAY 0.978723 (2975 1150);
PAINT WHITE (2975 1150);
DISPLAY INVISIBLE (2975 1150);
FORCEPROP 2 LAST SEC 1
J 0
(2975 1200);
DISPLAY 0.680851 (2975 1200);
PAINT MONO (2975 1200);
DISPLAY INVISIBLE (2975 1200);
FORCEPROP 2 LAST SEC_TYPE 0603V
J 0
(2975 1200);
DISPLAY 1.021277 (2975 1200);
PAINT ORANGE (2975 1200);
DISPLAY INVISIBLE (2975 1200);
FORCEPROP 2 LAST CDS_SEC 1
J 0
(2975 1150);
PAINT ORANGE (2975 1150);
DISPLAY INVISIBLE (2975 1150);
FORCEPROP 2 LAST CDS_LOCATION C5F2
J 0
(2975 1100);
DISPLAY 0.617021 (2975 1100);
PAINT AQUA (2975 1100);
DISPLAY INVISIBLE (2975 1100);
FORCEADD CAP_A..1
(3275 1000);
FORCEPROP 1 LASTPIN (3275 900) $PN 2
J 0
(3285 880);
DISPLAY 0.617021 (3285 880);
PAINT ORANGE (3285 880);
FORCEPROP 1 LAST MATERIAL X5R
J 0
(3325 900);
DISPLAY 0.617021 (3325 900);
PAINT SKYBLUE (3325 900);
FORCEPROP 1 LAST PACK_TYPE 0603V
J 0
(3325 800);
DISPLAY 0.617021 (3325 800);
PAINT SKYBLUE (3325 800);
FORCEPROP 1 LAST TOLERANCE 20%
J 0
(3325 950);
DISPLAY 0.617021 (3325 950);
PAINT SKYBLUE (3325 950);
FORCEPROP 1 LAST PART_NUMBER 602433-106
J 0
(3325 850);
DISPLAY 0.617021 (3325 850);
PAINT BLUE (3325 850);
FORCEPROP 1 LAST VOLTAGE 4V
J 0
(3325 1000);
DISPLAY 0.617021 (3325 1000);
PAINT SKYBLUE (3325 1000);
FORCEPROP 1 LASTPIN (3275 1100) $PN 1
J 0
(3285 1080);
DISPLAY 0.617021 (3285 1080);
PAINT ORANGE (3285 1080);
FORCEPROP 1 LAST LOCATION C5F1
J 0
(3325 1100);
DISPLAY 0.617021 (3325 1100);
PAINT AQUA (3325 1100);
FORCEPROP 1 LAST VALUE 47UF
J 0
(3325 1050);
DISPLAY 0.617021 (3325 1050);
PAINT SKYBLUE (3325 1050);
FORCEPROP 2 LAST CDS_LIB dev_discrete
J 0
(3275 1000);
PAINT ORANGE (3275 1000);
DISPLAY INVISIBLE (3275 1000);
FORCEPROP 2 LAST CDS_LOCATION C5F1
J 0
(3325 1100);
DISPLAY 0.617021 (3325 1100);
PAINT AQUA (3325 1100);
DISPLAY INVISIBLE (3325 1100);
FORCEPROP 2 LAST CDS_SEC 1
J 0
(3325 1150);
PAINT ORANGE (3325 1150);
DISPLAY INVISIBLE (3325 1150);
FORCEPROP 2 LAST SEC_TYPE 0603V
J 0
(3325 1200);
DISPLAY 1.021277 (3325 1200);
PAINT ORANGE (3325 1200);
DISPLAY INVISIBLE (3325 1200);
FORCEPROP 2 LAST SEC 1
J 0
(3325 1200);
DISPLAY 0.680851 (3325 1200);
PAINT MONO (3325 1200);
DISPLAY INVISIBLE (3325 1200);
FORCEPROP 1 LAST PATH I206
J 0
(3325 1150);
DISPLAY 0.978723 (3325 1150);
PAINT WHITE (3325 1150);
DISPLAY INVISIBLE (3325 1150);
FORCEADD CAP_A..1
(3675 1000);
FORCEPROP 1 LASTPIN (3675 900) $PN 2
J 0
(3685 880);
DISPLAY 0.617021 (3685 880);
PAINT ORANGE (3685 880);
FORCEPROP 1 LAST MATERIAL X5R
J 0
(3725 900);
DISPLAY 0.617021 (3725 900);
PAINT SKYBLUE (3725 900);
FORCEPROP 1 LAST TOLERANCE 20%
J 0
(3725 950);
DISPLAY 0.617021 (3725 950);
PAINT SKYBLUE (3725 950);
FORCEPROP 1 LAST PACK_TYPE 0603V
J 0
(3725 800);
DISPLAY 0.617021 (3725 800);
PAINT SKYBLUE (3725 800);
FORCEPROP 1 LAST PART_NUMBER 602433-106
J 0
(3725 850);
DISPLAY 0.617021 (3725 850);
PAINT BLUE (3725 850);
FORCEPROP 1 LAST VOLTAGE 4V
J 0
(3725 1000);
DISPLAY 0.617021 (3725 1000);
PAINT SKYBLUE (3725 1000);
FORCEPROP 1 LASTPIN (3675 1100) $PN 1
J 0
(3685 1080);
DISPLAY 0.617021 (3685 1080);
PAINT ORANGE (3685 1080);
FORCEPROP 1 LAST LOCATION C5G10
J 0
(3725 1100);
DISPLAY 0.617021 (3725 1100);
PAINT AQUA (3725 1100);
FORCEPROP 1 LAST VALUE 47UF
J 0
(3725 1050);
DISPLAY 0.617021 (3725 1050);
PAINT SKYBLUE (3725 1050);
FORCEPROP 2 LAST CDS_LIB dev_discrete
J 0
(3675 1000);
PAINT ORANGE (3675 1000);
DISPLAY INVISIBLE (3675 1000);
FORCEPROP 2 LAST CDS_LOCATION C5G10
J 0
(3725 1100);
DISPLAY 0.617021 (3725 1100);
PAINT AQUA (3725 1100);
DISPLAY INVISIBLE (3725 1100);
FORCEPROP 2 LAST CDS_SEC 1
J 0
(3725 1150);
PAINT ORANGE (3725 1150);
DISPLAY INVISIBLE (3725 1150);
FORCEPROP 2 LAST SEC_TYPE 0603V
J 0
(3725 1200);
DISPLAY 1.021277 (3725 1200);
PAINT ORANGE (3725 1200);
DISPLAY INVISIBLE (3725 1200);
FORCEPROP 2 LAST SEC 1
J 0
(3725 1200);
DISPLAY 0.680851 (3725 1200);
PAINT MONO (3725 1200);
DISPLAY INVISIBLE (3725 1200);
FORCEPROP 1 LAST PATH I207
J 0
(3725 1150);
DISPLAY 0.978723 (3725 1150);
PAINT WHITE (3725 1150);
DISPLAY INVISIBLE (3725 1150);
FORCEADD CAP_A..1
(4000 1725);
FORCEPROP 1 LASTPIN (4000 1625) $PN 2
J 0
(4010 1605);
DISPLAY 0.617021 (4010 1605);
PAINT ORANGE (4010 1605);
FORCEPROP 1 LASTPIN (4000 1825) $PN 1
J 0
(4010 1805);
DISPLAY 0.617021 (4010 1805);
PAINT ORANGE (4010 1805);
FORCEPROP 1 LAST MATERIAL X5R
J 0
(4050 1625);
DISPLAY 0.617021 (4050 1625);
PAINT SKYBLUE (4050 1625);
FORCEPROP 1 LAST VOLTAGE 4V
J 0
(4050 1725);
DISPLAY 0.617021 (4050 1725);
PAINT SKYBLUE (4050 1725);
FORCEPROP 1 LAST PACK_TYPE 0603V
J 0
(4050 1525);
DISPLAY 0.617021 (4050 1525);
PAINT SKYBLUE (4050 1525);
FORCEPROP 1 LAST TOLERANCE 20%
J 0
(4050 1675);
DISPLAY 0.617021 (4050 1675);
PAINT SKYBLUE (4050 1675);
FORCEPROP 1 LAST VALUE 47UF
J 0
(4050 1775);
DISPLAY 0.617021 (4050 1775);
PAINT SKYBLUE (4050 1775);
FORCEPROP 1 LAST PART_NUMBER 602433-106
J 0
(4050 1575);
DISPLAY 0.617021 (4050 1575);
PAINT BLUE (4050 1575);
FORCEPROP 1 LAST LOCATION C5T2
J 0
(4050 1825);
DISPLAY 0.617021 (4050 1825);
PAINT AQUA (4050 1825);
FORCEPROP 2 LAST CDS_LIB dev_discrete
J 0
(4000 1725);
PAINT ORANGE (4000 1725);
DISPLAY INVISIBLE (4000 1725);
FORCEPROP 1 LAST PATH I208
J 0
(4050 1875);
DISPLAY 0.978723 (4050 1875);
PAINT WHITE (4050 1875);
DISPLAY INVISIBLE (4050 1875);
FORCEPROP 2 LAST SEC 1
J 0
(4050 1925);
DISPLAY 0.680851 (4050 1925);
PAINT MONO (4050 1925);
DISPLAY INVISIBLE (4050 1925);
FORCEPROP 2 LAST SEC_TYPE 0603V
J 0
(4050 1925);
DISPLAY 1.021277 (4050 1925);
PAINT ORANGE (4050 1925);
DISPLAY INVISIBLE (4050 1925);
FORCEPROP 2 LAST CDS_SEC 1
J 0
(4050 1875);
PAINT ORANGE (4050 1875);
DISPLAY INVISIBLE (4050 1875);
FORCEPROP 2 LAST CDS_LOCATION C5T2
J 0
(4050 1825);
DISPLAY 0.617021 (4050 1825);
PAINT AQUA (4050 1825);
DISPLAY INVISIBLE (4050 1825);
FORCEADD CAP_A..1
(4350 1725);
FORCEPROP 1 LAST PACK_TYPE 0603V
J 0
(4400 1525);
DISPLAY 0.617021 (4400 1525);
PAINT SKYBLUE (4400 1525);
FORCEPROP 1 LASTPIN (4350 1825) $PN 1
J 0
(4360 1805);
DISPLAY 0.617021 (4360 1805);
PAINT ORANGE (4360 1805);
FORCEPROP 1 LASTPIN (4350 1625) $PN 2
J 0
(4360 1605);
DISPLAY 0.617021 (4360 1605);
PAINT ORANGE (4360 1605);
FORCEPROP 1 LAST MATERIAL X5R
J 0
(4400 1625);
DISPLAY 0.617021 (4400 1625);
PAINT SKYBLUE (4400 1625);
FORCEPROP 1 LAST VOLTAGE 4V
J 0
(4400 1725);
DISPLAY 0.617021 (4400 1725);
PAINT SKYBLUE (4400 1725);
FORCEPROP 1 LAST TOLERANCE 20%
J 0
(4400 1675);
DISPLAY 0.617021 (4400 1675);
PAINT SKYBLUE (4400 1675);
FORCEPROP 1 LAST VALUE 47UF
J 0
(4400 1775);
DISPLAY 0.617021 (4400 1775);
PAINT SKYBLUE (4400 1775);
FORCEPROP 1 LAST LOCATION C5U11
J 0
(4400 1825);
DISPLAY 0.617021 (4400 1825);
PAINT AQUA (4400 1825);
FORCEPROP 1 LAST PART_NUMBER 602433-106
J 0
(4400 1575);
DISPLAY 0.617021 (4400 1575);
PAINT BLUE (4400 1575);
FORCEPROP 2 LAST CDS_LIB dev_discrete
J 0
(4350 1725);
PAINT ORANGE (4350 1725);
DISPLAY INVISIBLE (4350 1725);
FORCEPROP 2 LAST CDS_LOCATION C5U11
J 0
(4400 1825);
DISPLAY 0.617021 (4400 1825);
PAINT AQUA (4400 1825);
DISPLAY INVISIBLE (4400 1825);
FORCEPROP 2 LAST CDS_SEC 1
J 0
(4400 1875);
PAINT ORANGE (4400 1875);
DISPLAY INVISIBLE (4400 1875);
FORCEPROP 2 LAST SEC_TYPE 0603V
J 0
(4400 1925);
DISPLAY 1.021277 (4400 1925);
PAINT ORANGE (4400 1925);
DISPLAY INVISIBLE (4400 1925);
FORCEPROP 2 LAST SEC 1
J 0
(4400 1925);
DISPLAY 0.680851 (4400 1925);
PAINT MONO (4400 1925);
DISPLAY INVISIBLE (4400 1925);
FORCEPROP 1 LAST PATH I209
J 0
(4400 1875);
DISPLAY 0.978723 (4400 1875);
PAINT WHITE (4400 1875);
DISPLAY INVISIBLE (4400 1875);
FORCEADD CAP_A..1
(4750 1725);
FORCEPROP 1 LAST PACK_TYPE 0603V
J 0
(4800 1525);
DISPLAY 0.617021 (4800 1525);
PAINT SKYBLUE (4800 1525);
FORCEPROP 1 LASTPIN (4750 1625) $PN 2
J 0
(4760 1605);
DISPLAY 0.617021 (4760 1605);
PAINT ORANGE (4760 1605);
FORCEPROP 1 LAST VOLTAGE 4V
J 0
(4800 1725);
DISPLAY 0.617021 (4800 1725);
PAINT SKYBLUE (4800 1725);
FORCEPROP 1 LASTPIN (4750 1825) $PN 1
J 0
(4760 1805);
DISPLAY 0.617021 (4760 1805);
PAINT ORANGE (4760 1805);
FORCEPROP 1 LAST LOCATION C5T13
J 0
(4800 1825);
DISPLAY 0.617021 (4800 1825);
PAINT AQUA (4800 1825);
FORCEPROP 1 LAST PART_NUMBER 602433-106
J 0
(4800 1575);
DISPLAY 0.617021 (4800 1575);
PAINT BLUE (4800 1575);
FORCEPROP 1 LAST VALUE 47UF
J 0
(4800 1775);
DISPLAY 0.617021 (4800 1775);
PAINT SKYBLUE (4800 1775);
FORCEPROP 1 LAST TOLERANCE 20%
J 0
(4800 1675);
DISPLAY 0.617021 (4800 1675);
PAINT SKYBLUE (4800 1675);
FORCEPROP 1 LAST MATERIAL X5R
J 0
(4800 1625);
DISPLAY 0.617021 (4800 1625);
PAINT SKYBLUE (4800 1625);
FORCEPROP 2 LAST CDS_LIB dev_discrete
J 0
(4750 1725);
PAINT ORANGE (4750 1725);
DISPLAY INVISIBLE (4750 1725);
FORCEPROP 1 LAST PATH I210
J 0
(4800 1875);
DISPLAY 0.978723 (4800 1875);
PAINT WHITE (4800 1875);
DISPLAY INVISIBLE (4800 1875);
FORCEPROP 2 LAST SEC 1
J 0
(4800 1925);
DISPLAY 0.680851 (4800 1925);
PAINT MONO (4800 1925);
DISPLAY INVISIBLE (4800 1925);
FORCEPROP 2 LAST SEC_TYPE 0603V
J 0
(4800 1925);
DISPLAY 1.021277 (4800 1925);
PAINT ORANGE (4800 1925);
DISPLAY INVISIBLE (4800 1925);
FORCEPROP 2 LAST CDS_SEC 1
J 0
(4800 1875);
PAINT ORANGE (4800 1875);
DISPLAY INVISIBLE (4800 1875);
FORCEPROP 2 LAST CDS_LOCATION C5T13
J 0
(4800 1825);
DISPLAY 0.617021 (4800 1825);
PAINT AQUA (4800 1825);
DISPLAY INVISIBLE (4800 1825);
FORCEADD CAP_A..1
(3650 1725);
FORCEPROP 1 LAST PACK_TYPE 0603V
J 0
(3700 1525);
DISPLAY 0.617021 (3700 1525);
PAINT SKYBLUE (3700 1525);
FORCEPROP 1 LAST TOLERANCE 20%
J 0
(3700 1675);
DISPLAY 0.617021 (3700 1675);
PAINT SKYBLUE (3700 1675);
FORCEPROP 1 LAST VOLTAGE 4V
J 0
(3700 1725);
DISPLAY 0.617021 (3700 1725);
PAINT SKYBLUE (3700 1725);
FORCEPROP 1 LAST MATERIAL X5R
J 0
(3700 1625);
DISPLAY 0.617021 (3700 1625);
PAINT SKYBLUE (3700 1625);
FORCEPROP 1 LASTPIN (3650 1625) $PN 2
J 0
(3660 1605);
DISPLAY 0.617021 (3660 1605);
PAINT ORANGE (3660 1605);
FORCEPROP 1 LAST VALUE 47UF
J 0
(3700 1775);
DISPLAY 0.617021 (3700 1775);
PAINT SKYBLUE (3700 1775);
FORCEPROP 1 LASTPIN (3650 1825) $PN 1
J 0
(3660 1805);
DISPLAY 0.617021 (3660 1805);
PAINT ORANGE (3660 1805);
FORCEPROP 1 LAST LOCATION C5T4
J 0
(3700 1825);
DISPLAY 0.617021 (3700 1825);
PAINT AQUA (3700 1825);
FORCEPROP 1 LAST PART_NUMBER 602433-106
J 0
(3700 1575);
DISPLAY 0.617021 (3700 1575);
PAINT BLUE (3700 1575);
FORCEPROP 2 LAST CDS_LIB dev_discrete
J 0
(3650 1725);
PAINT ORANGE (3650 1725);
DISPLAY INVISIBLE (3650 1725);
FORCEPROP 1 LAST PATH I211
J 0
(3700 1875);
DISPLAY 0.978723 (3700 1875);
PAINT WHITE (3700 1875);
DISPLAY INVISIBLE (3700 1875);
FORCEPROP 2 LAST SEC 1
J 0
(3700 1925);
DISPLAY 0.680851 (3700 1925);
PAINT MONO (3700 1925);
DISPLAY INVISIBLE (3700 1925);
FORCEPROP 2 LAST SEC_TYPE 0603V
J 0
(3700 1925);
DISPLAY 1.021277 (3700 1925);
PAINT ORANGE (3700 1925);
DISPLAY INVISIBLE (3700 1925);
FORCEPROP 2 LAST CDS_SEC 1
J 0
(3700 1875);
PAINT ORANGE (3700 1875);
DISPLAY INVISIBLE (3700 1875);
FORCEPROP 2 LAST CDS_LOCATION C5T4
J 0
(3700 1825);
DISPLAY 0.617021 (3700 1825);
PAINT AQUA (3700 1825);
DISPLAY INVISIBLE (3700 1825);
FORCEADD CAP_A..1
(3250 1725);
FORCEPROP 1 LAST PACK_TYPE 0603V
J 0
(3300 1525);
DISPLAY 0.617021 (3300 1525);
PAINT SKYBLUE (3300 1525);
FORCEPROP 1 LASTPIN (3250 1625) $PN 2
J 0
(3260 1605);
DISPLAY 0.617021 (3260 1605);
PAINT ORANGE (3260 1605);
FORCEPROP 1 LASTPIN (3250 1825) $PN 1
J 0
(3260 1805);
DISPLAY 0.617021 (3260 1805);
PAINT ORANGE (3260 1805);
FORCEPROP 1 LAST LOCATION C5T1
J 0
(3300 1825);
DISPLAY 0.617021 (3300 1825);
PAINT AQUA (3300 1825);
FORCEPROP 1 LAST VALUE 47UF
J 0
(3300 1775);
DISPLAY 0.617021 (3300 1775);
PAINT SKYBLUE (3300 1775);
FORCEPROP 1 LAST MATERIAL X5R
J 0
(3300 1625);
DISPLAY 0.617021 (3300 1625);
PAINT SKYBLUE (3300 1625);
FORCEPROP 1 LAST VOLTAGE 4V
J 0
(3300 1725);
DISPLAY 0.617021 (3300 1725);
PAINT SKYBLUE (3300 1725);
FORCEPROP 1 LAST TOLERANCE 20%
J 0
(3300 1675);
DISPLAY 0.617021 (3300 1675);
PAINT SKYBLUE (3300 1675);
FORCEPROP 1 LAST PART_NUMBER 602433-106
J 0
(3300 1575);
DISPLAY 0.617021 (3300 1575);
PAINT BLUE (3300 1575);
FORCEPROP 2 LAST CDS_LIB dev_discrete
J 0
(3250 1725);
PAINT ORANGE (3250 1725);
DISPLAY INVISIBLE (3250 1725);
FORCEPROP 1 LAST PATH I212
J 0
(3300 1875);
DISPLAY 0.978723 (3300 1875);
PAINT WHITE (3300 1875);
DISPLAY INVISIBLE (3300 1875);
FORCEPROP 2 LAST SEC 1
J 0
(3300 1925);
DISPLAY 0.680851 (3300 1925);
PAINT MONO (3300 1925);
DISPLAY INVISIBLE (3300 1925);
FORCEPROP 2 LAST SEC_TYPE 0603V
J 0
(3300 1925);
DISPLAY 1.021277 (3300 1925);
PAINT ORANGE (3300 1925);
DISPLAY INVISIBLE (3300 1925);
FORCEPROP 2 LAST CDS_SEC 1
J 0
(3300 1875);
PAINT ORANGE (3300 1875);
DISPLAY INVISIBLE (3300 1875);
FORCEPROP 2 LAST CDS_LOCATION C5T1
J 0
(3300 1825);
DISPLAY 0.617021 (3300 1825);
PAINT AQUA (3300 1825);
DISPLAY INVISIBLE (3300 1825);
FORCEADD CAP_A..1
(2900 1725);
FORCEPROP 1 LASTPIN (2900 1625) $PN 2
J 0
(2910 1605);
DISPLAY 0.617021 (2910 1605);
PAINT ORANGE (2910 1605);
FORCEPROP 1 LAST MATERIAL X5R
J 0
(2950 1625);
DISPLAY 0.617021 (2950 1625);
PAINT SKYBLUE (2950 1625);
FORCEPROP 1 LAST VOLTAGE 4V
J 0
(2950 1725);
DISPLAY 0.617021 (2950 1725);
PAINT SKYBLUE (2950 1725);
FORCEPROP 1 LAST TOLERANCE 20%
J 0
(2950 1675);
DISPLAY 0.617021 (2950 1675);
PAINT SKYBLUE (2950 1675);
FORCEPROP 1 LAST VALUE 47UF
J 0
(2950 1775);
DISPLAY 0.617021 (2950 1775);
PAINT SKYBLUE (2950 1775);
FORCEPROP 1 LASTPIN (2900 1825) $PN 1
J 0
(2910 1805);
DISPLAY 0.617021 (2910 1805);
PAINT ORANGE (2910 1805);
FORCEPROP 1 LAST PACK_TYPE 0603V
J 0
(2950 1525);
DISPLAY 0.617021 (2950 1525);
PAINT SKYBLUE (2950 1525);
FORCEPROP 1 LAST PART_NUMBER 602433-106
J 0
(2950 1575);
DISPLAY 0.617021 (2950 1575);
PAINT BLUE (2950 1575);
FORCEPROP 1 LAST LOCATION C5G19
J 0
(2950 1825);
DISPLAY 0.617021 (2950 1825);
PAINT AQUA (2950 1825);
FORCEPROP 2 LAST CDS_LIB dev_discrete
J 0
(2900 1725);
PAINT ORANGE (2900 1725);
DISPLAY INVISIBLE (2900 1725);
FORCEPROP 1 LAST PATH I213
J 0
(2950 1875);
DISPLAY 0.978723 (2950 1875);
PAINT WHITE (2950 1875);
DISPLAY INVISIBLE (2950 1875);
FORCEPROP 2 LAST SEC 1
J 0
(2950 1925);
DISPLAY 0.680851 (2950 1925);
PAINT MONO (2950 1925);
DISPLAY INVISIBLE (2950 1925);
FORCEPROP 2 LAST SEC_TYPE 0603V
J 0
(2950 1925);
DISPLAY 1.021277 (2950 1925);
PAINT ORANGE (2950 1925);
DISPLAY INVISIBLE (2950 1925);
FORCEPROP 2 LAST CDS_SEC 1
J 0
(2950 1875);
PAINT ORANGE (2950 1875);
DISPLAY INVISIBLE (2950 1875);
FORCEPROP 2 LAST CDS_LOCATION C5G19
J 0
(2950 1825);
DISPLAY 0.617021 (2950 1825);
PAINT AQUA (2950 1825);
DISPLAY INVISIBLE (2950 1825);
FORCEADD PVDDQ_ABC..1
(-900 3125);
FORCEPROP 3 LASTPIN (-900 3075) SIG_NAME PVDDQ_ABC\g
J 0
(-890 3085);
DISPLAY 0.659574 (-890 3085);
PAINT MONO (-890 3085);
DISPLAY INVISIBLE (-890 3085);
FORCEPROP 2 LAST BOM_COST MEM_VRD_PVDDQ_CD
J 0
(-825 3225);
PAINT MONO (-825 3225);
DISPLAY INVISIBLE (-825 3225);
FORCEPROP 2 LAST CDS_LIB mstr_symbols
J 0
(-900 3125);
PAINT ORANGE (-900 3125);
DISPLAY INVISIBLE (-900 3125);
FORCEPROP 1 LAST BODY_TYPE PLUMBING
J 0
(-945 3082);
DISPLAY 0.340426 (-945 3082);
PAINT GREEN (-945 3082);
DISPLAY INVISIBLE (-945 3082);
FORCEPROP 1 LAST PATH I214
J 0
(-850 3150);
DISPLAY 0.872340 (-850 3150);
PAINT AQUA (-850 3150);
DISPLAY INVISIBLE (-850 3150);
FORCEPROP 2 LAST ROOM VDDQ_ABC_PWR_VR
J 0
(-650 3225);
PAINT ORANGE (-650 3225);
DISPLAY INVISIBLE (-650 3225);
FORCEPROP 1 LAST HDL_POWER PVDDQ_ABC
J 1
(-900 3175);
DISPLAY 0.872340 (-900 3175);
PAINT GREEN (-900 3175);
DISPLAY INVISIBLE (-900 3175);
FORCEPROP 1 LAST VOLTAGE 1.2V
J 0
(-945 3082);
DISPLAY 0.340426 (-945 3082);
PAINT SKYBLUE (-945 3082);
DISPLAY INVISIBLE (-945 3082);
FORCEADD GND..1
(-1300 2500);
FORCEPROP 3 LASTPIN (-1300 2550) SIG_NAME GND\g
J 0
(-1290 2560);
DISPLAY 0.659574 (-1290 2560);
PAINT MONO (-1290 2560);
DISPLAY INVISIBLE (-1290 2560);
FORCEPROP 2 LAST ROOM VDDQ_ABC_PWR_VR
J 0
(-1850 2575);
PAINT ORANGE (-1850 2575);
DISPLAY INVISIBLE (-1850 2575);
FORCEPROP 2 LAST BOM_COST MEM_VRD_PVDDQ_CD
J 0
(-1625 2575);
PAINT MONO (-1625 2575);
DISPLAY INVISIBLE (-1625 2575);
FORCEPROP 1 LAST SIZE 1B
J 0
(-1225 2450);
DISPLAY 0.893617 (-1225 2450);
PAINT GREEN (-1225 2450);
DISPLAY INVISIBLE (-1225 2450);
FORCEPROP 2 LAST CDS_LIB mstr_symbols
J 0
(-1300 2500);
PAINT ORANGE (-1300 2500);
DISPLAY INVISIBLE (-1300 2500);
FORCEPROP 1 LAST BODY_TYPE PLUMBING
J 0
(-1345 2457);
DISPLAY 0.340426 (-1345 2457);
PAINT GREEN (-1345 2457);
DISPLAY INVISIBLE (-1345 2457);
FORCEPROP 1 LAST PATH I215
J 0
(-1225 2500);
DISPLAY 0.872340 (-1225 2500);
PAINT AQUA (-1225 2500);
DISPLAY INVISIBLE (-1225 2500);
FORCEPROP 1 LAST VOLTAGE 0
J 0
(-1300 2500);
PAINT SKYBLUE (-1300 2500);
DISPLAY INVISIBLE (-1300 2500);
FORCEPROP 1 LAST HDL_POWER GND
J 0
(-1300 2650);
DISPLAY 0.893617 (-1300 2650);
PAINT GREEN (-1300 2650);
DISPLAY INVISIBLE (-1300 2650);
FORCEADD CAP_A..1
(2550 50);
FORCEPROP 1 LAST PART_NUMBER E15431-004
J 0
(2600 -100);
DISPLAY 0.617021 (2600 -100);
PAINT BLUE (2600 -100);
FORCEPROP 1 LAST PACK_TYPE 0603V
J 0
(2600 -150);
DISPLAY 0.617021 (2600 -150);
PAINT SKYBLUE (2600 -150);
FORCEPROP 1 LAST MATERIAL X6S
J 0
(2600 -50);
DISPLAY 0.617021 (2600 -50);
PAINT SKYBLUE (2600 -50);
FORCEPROP 1 LAST LOCATION C5T5
J 0
(2600 150);
DISPLAY 0.617021 (2600 150);
PAINT AQUA (2600 150);
FORCEPROP 1 LAST VALUE 22.0UF
J 0
(2600 100);
DISPLAY 0.617021 (2600 100);
PAINT SKYBLUE (2600 100);
FORCEPROP 1 LAST VOLTAGE 4V
J 0
(2600 50);
DISPLAY 0.617021 (2600 50);
PAINT SKYBLUE (2600 50);
FORCEPROP 1 LAST TOLERANCE 20%
J 0
(2600 0);
DISPLAY 0.617021 (2600 0);
PAINT SKYBLUE (2600 0);
FORCEPROP 1 LASTPIN (2550 -50) $PN 2
J 0
(2560 -70);
DISPLAY 0.787234 (2560 -70);
PAINT ORANGE (2560 -70);
DISPLAY INVISIBLE (2560 -70);
FORCEPROP 2 LAST CDS_LIB dev_discrete
J 0
(2550 50);
PAINT ORANGE (2550 50);
DISPLAY INVISIBLE (2550 50);
FORCEPROP 1 LASTPIN (2550 150) $PN 1
J 0
(2560 130);
DISPLAY 0.787234 (2560 130);
PAINT ORANGE (2560 130);
DISPLAY INVISIBLE (2560 130);
FORCEPROP 0 LAST ROOM PVDDQ_ABC
J 0
(2600 250);
DISPLAY 1.021277 (2600 250);
PAINT ORANGE (2600 250);
DISPLAY INVISIBLE (2600 250);
FORCEPROP 1 LAST PATH I216
J 0
(2600 200);
DISPLAY 0.978723 (2600 200);
PAINT WHITE (2600 200);
DISPLAY INVISIBLE (2600 200);
FORCEPROP 2 LAST $SEC 1
J 0
(2600 250);
PAINT MONO (2600 250);
DISPLAY INVISIBLE (2600 250);
FORCEPROP 2 LAST CDS_SEC 1
J 0
(2600 250);
PAINT MONO (2600 250);
DISPLAY INVISIBLE (2600 250);
FORCEPROP 2 LAST CDS_LOCATION C5T5
J 0
(2600 150);
DISPLAY 0.617021 (2600 150);
PAINT AQUA (2600 150);
DISPLAY INVISIBLE (2600 150);
FORCEADD CAP_A..1
(2525 -650);
FORCEPROP 1 LAST LOCATION C5G3
J 0
(2575 -550);
DISPLAY 0.617021 (2575 -550);
PAINT AQUA (2575 -550);
FORCEPROP 1 LAST PART_NUMBER E15431-004
J 0
(2575 -800);
DISPLAY 0.617021 (2575 -800);
PAINT BLUE (2575 -800);
FORCEPROP 1 LAST VALUE 22.0UF
J 0
(2575 -600);
DISPLAY 0.617021 (2575 -600);
PAINT SKYBLUE (2575 -600);
FORCEPROP 1 LAST TOLERANCE 20%
J 0
(2575 -700);
DISPLAY 0.617021 (2575 -700);
PAINT SKYBLUE (2575 -700);
FORCEPROP 1 LAST PACK_TYPE 0603V
J 0
(2575 -850);
DISPLAY 0.617021 (2575 -850);
PAINT SKYBLUE (2575 -850);
FORCEPROP 1 LAST VOLTAGE 4V
J 0
(2575 -650);
DISPLAY 0.617021 (2575 -650);
PAINT SKYBLUE (2575 -650);
FORCEPROP 1 LAST MATERIAL X6S
J 0
(2575 -750);
DISPLAY 0.617021 (2575 -750);
PAINT SKYBLUE (2575 -750);
FORCEPROP 2 LAST CDS_LIB dev_discrete
J 0
(2525 -650);
PAINT ORANGE (2525 -650);
DISPLAY INVISIBLE (2525 -650);
FORCEPROP 1 LASTPIN (2525 -550) $PN 1
J 0
(2535 -570);
DISPLAY 0.787234 (2535 -570);
PAINT ORANGE (2535 -570);
DISPLAY INVISIBLE (2535 -570);
FORCEPROP 1 LASTPIN (2525 -750) $PN 2
J 0
(2535 -770);
DISPLAY 0.787234 (2535 -770);
PAINT ORANGE (2535 -770);
DISPLAY INVISIBLE (2535 -770);
FORCEPROP 2 LAST CDS_LOCATION C5G3
J 0
(2575 -550);
DISPLAY 0.617021 (2575 -550);
PAINT AQUA (2575 -550);
DISPLAY INVISIBLE (2575 -550);
FORCEPROP 0 LAST ROOM PVDDQ_ABC
J 0
(2575 -450);
DISPLAY 1.021277 (2575 -450);
PAINT ORANGE (2575 -450);
DISPLAY INVISIBLE (2575 -450);
FORCEPROP 1 LAST PATH I217
J 0
(2575 -500);
DISPLAY 0.978723 (2575 -500);
PAINT WHITE (2575 -500);
DISPLAY INVISIBLE (2575 -500);
FORCEPROP 2 LAST $SEC 1
J 0
(2575 -450);
PAINT MONO (2575 -450);
DISPLAY INVISIBLE (2575 -450);
FORCEPROP 2 LAST CDS_SEC 1
J 0
(2575 -450);
PAINT MONO (2575 -450);
DISPLAY INVISIBLE (2575 -450);
FORCEADD CAP_A..1
(2275 50);
FORCEPROP 1 LAST PACK_TYPE 0603V
J 0
(2325 -150);
DISPLAY 0.617021 (2325 -150);
PAINT SKYBLUE (2325 -150);
FORCEPROP 1 LAST MATERIAL X6S
J 0
(2325 -50);
DISPLAY 0.617021 (2325 -50);
PAINT SKYBLUE (2325 -50);
FORCEPROP 1 LAST PART_NUMBER E15431-004
J 0
(2325 -100);
DISPLAY 0.617021 (2325 -100);
PAINT BLUE (2325 -100);
FORCEPROP 1 LAST TOLERANCE 20%
J 0
(2325 0);
DISPLAY 0.617021 (2325 0);
PAINT SKYBLUE (2325 0);
FORCEPROP 1 LAST LOCATION C5T6
J 0
(2325 150);
DISPLAY 0.617021 (2325 150);
PAINT AQUA (2325 150);
FORCEPROP 1 LAST VALUE 22.0UF
J 0
(2325 100);
DISPLAY 0.617021 (2325 100);
PAINT SKYBLUE (2325 100);
FORCEPROP 1 LAST VOLTAGE 4V
J 0
(2325 50);
DISPLAY 0.617021 (2325 50);
PAINT SKYBLUE (2325 50);
FORCEPROP 1 LASTPIN (2275 -50) $PN 2
J 0
(2285 -70);
DISPLAY 0.787234 (2285 -70);
PAINT ORANGE (2285 -70);
DISPLAY INVISIBLE (2285 -70);
FORCEPROP 2 LAST CDS_LIB dev_discrete
J 0
(2275 50);
PAINT ORANGE (2275 50);
DISPLAY INVISIBLE (2275 50);
FORCEPROP 1 LASTPIN (2275 150) $PN 1
J 0
(2285 130);
DISPLAY 0.787234 (2285 130);
PAINT ORANGE (2285 130);
DISPLAY INVISIBLE (2285 130);
FORCEPROP 1 LAST PATH I218
J 0
(2325 200);
DISPLAY 0.978723 (2325 200);
PAINT WHITE (2325 200);
DISPLAY INVISIBLE (2325 200);
FORCEPROP 2 LAST CDS_LOCATION C5T6
J 0
(2325 150);
DISPLAY 0.617021 (2325 150);
PAINT AQUA (2325 150);
DISPLAY INVISIBLE (2325 150);
FORCEPROP 0 LAST ROOM PVDDQ_ABC
J 0
(2325 250);
DISPLAY 1.021277 (2325 250);
PAINT ORANGE (2325 250);
DISPLAY INVISIBLE (2325 250);
FORCEPROP 2 LAST $SEC 1
J 0
(2325 250);
PAINT MONO (2325 250);
DISPLAY INVISIBLE (2325 250);
FORCEPROP 2 LAST CDS_SEC 1
J 0
(2325 250);
PAINT MONO (2325 250);
DISPLAY INVISIBLE (2325 250);
FORCEADD CAP_A..1
(1975 50);
FORCEPROP 1 LAST MATERIAL X6S
J 0
(2025 -50);
DISPLAY 0.617021 (2025 -50);
PAINT SKYBLUE (2025 -50);
FORCEPROP 1 LAST PACK_TYPE 0603V
J 0
(2025 -150);
DISPLAY 0.617021 (2025 -150);
PAINT SKYBLUE (2025 -150);
FORCEPROP 1 LAST PART_NUMBER E15431-004
J 0
(2025 -100);
DISPLAY 0.617021 (2025 -100);
PAINT BLUE (2025 -100);
FORCEPROP 1 LAST TOLERANCE 20%
J 0
(2025 0);
DISPLAY 0.617021 (2025 0);
PAINT SKYBLUE (2025 0);
FORCEPROP 1 LAST VOLTAGE 4V
J 0
(2025 50);
DISPLAY 0.617021 (2025 50);
PAINT SKYBLUE (2025 50);
FORCEPROP 1 LAST VALUE 22.0UF
J 0
(2025 100);
DISPLAY 0.617021 (2025 100);
PAINT SKYBLUE (2025 100);
FORCEPROP 1 LAST LOCATION C5T7
J 0
(2025 150);
DISPLAY 0.617021 (2025 150);
PAINT AQUA (2025 150);
FORCEPROP 1 LASTPIN (1975 -50) $PN 2
J 0
(1985 -70);
DISPLAY 0.787234 (1985 -70);
PAINT ORANGE (1985 -70);
DISPLAY INVISIBLE (1985 -70);
FORCEPROP 2 LAST CDS_LIB dev_discrete
J 0
(1975 50);
PAINT ORANGE (1975 50);
DISPLAY INVISIBLE (1975 50);
FORCEPROP 1 LASTPIN (1975 150) $PN 1
J 0
(1985 130);
DISPLAY 0.787234 (1985 130);
PAINT ORANGE (1985 130);
DISPLAY INVISIBLE (1985 130);
FORCEPROP 1 LAST PATH I219
J 0
(2025 200);
DISPLAY 0.978723 (2025 200);
PAINT WHITE (2025 200);
DISPLAY INVISIBLE (2025 200);
FORCEPROP 2 LAST CDS_LOCATION C5T7
J 0
(2025 150);
DISPLAY 0.617021 (2025 150);
PAINT AQUA (2025 150);
DISPLAY INVISIBLE (2025 150);
FORCEPROP 0 LAST ROOM PVDDQ_ABC
J 0
(2025 250);
DISPLAY 1.021277 (2025 250);
PAINT ORANGE (2025 250);
DISPLAY INVISIBLE (2025 250);
FORCEPROP 2 LAST $SEC 1
J 0
(2025 250);
PAINT MONO (2025 250);
DISPLAY INVISIBLE (2025 250);
FORCEPROP 2 LAST CDS_SEC 1
J 0
(2025 250);
PAINT MONO (2025 250);
DISPLAY INVISIBLE (2025 250);
FORCEADD CAP_A..1
(2250 -650);
FORCEPROP 1 LAST MATERIAL X6S
J 0
(2300 -750);
DISPLAY 0.617021 (2300 -750);
PAINT SKYBLUE (2300 -750);
FORCEPROP 1 LAST VOLTAGE 4V
J 0
(2300 -650);
DISPLAY 0.617021 (2300 -650);
PAINT SKYBLUE (2300 -650);
FORCEPROP 1 LAST PACK_TYPE 0603V
J 0
(2300 -850);
DISPLAY 0.617021 (2300 -850);
PAINT SKYBLUE (2300 -850);
FORCEPROP 1 LAST TOLERANCE 20%
J 0
(2300 -700);
DISPLAY 0.617021 (2300 -700);
PAINT SKYBLUE (2300 -700);
FORCEPROP 1 LAST LOCATION C5G15
J 0
(2300 -550);
DISPLAY 0.617021 (2300 -550);
PAINT AQUA (2300 -550);
FORCEPROP 1 LAST PART_NUMBER E15431-004
J 0
(2300 -800);
DISPLAY 0.617021 (2300 -800);
PAINT BLUE (2300 -800);
FORCEPROP 1 LAST VALUE 22.0UF
J 0
(2300 -600);
DISPLAY 0.617021 (2300 -600);
PAINT SKYBLUE (2300 -600);
FORCEPROP 1 LASTPIN (2250 -750) $PN 2
J 0
(2260 -770);
DISPLAY 0.787234 (2260 -770);
PAINT ORANGE (2260 -770);
DISPLAY INVISIBLE (2260 -770);
FORCEPROP 1 LASTPIN (2250 -550) $PN 1
J 0
(2260 -570);
DISPLAY 0.787234 (2260 -570);
PAINT ORANGE (2260 -570);
DISPLAY INVISIBLE (2260 -570);
FORCEPROP 2 LAST CDS_LIB dev_discrete
J 0
(2250 -650);
PAINT ORANGE (2250 -650);
DISPLAY INVISIBLE (2250 -650);
FORCEPROP 2 LAST CDS_LOCATION C5G15
J 0
(2300 -550);
DISPLAY 0.617021 (2300 -550);
PAINT AQUA (2300 -550);
DISPLAY INVISIBLE (2300 -550);
FORCEPROP 2 LAST CDS_SEC 1
J 0
(2300 -450);
PAINT MONO (2300 -450);
DISPLAY INVISIBLE (2300 -450);
FORCEPROP 2 LAST $SEC 1
J 0
(2300 -450);
PAINT MONO (2300 -450);
DISPLAY INVISIBLE (2300 -450);
FORCEPROP 1 LAST PATH I220
J 0
(2300 -500);
DISPLAY 0.978723 (2300 -500);
PAINT WHITE (2300 -500);
DISPLAY INVISIBLE (2300 -500);
FORCEPROP 0 LAST ROOM PVDDQ_ABC
J 0
(2300 -450);
DISPLAY 1.021277 (2300 -450);
PAINT ORANGE (2300 -450);
DISPLAY INVISIBLE (2300 -450);
FORCEADD CAP_A..1
(1950 -650);
FORCEPROP 1 LAST MATERIAL X6S
J 0
(2000 -750);
DISPLAY 0.617021 (2000 -750);
PAINT SKYBLUE (2000 -750);
FORCEPROP 1 LAST VOLTAGE 4V
J 0
(2000 -650);
DISPLAY 0.617021 (2000 -650);
PAINT SKYBLUE (2000 -650);
FORCEPROP 1 LAST PACK_TYPE 0603V
J 0
(2000 -850);
DISPLAY 0.617021 (2000 -850);
PAINT SKYBLUE (2000 -850);
FORCEPROP 1 LAST TOLERANCE 20%
J 0
(2000 -700);
DISPLAY 0.617021 (2000 -700);
PAINT SKYBLUE (2000 -700);
FORCEPROP 1 LAST VALUE 22.0UF
J 0
(2000 -600);
DISPLAY 0.617021 (2000 -600);
PAINT SKYBLUE (2000 -600);
FORCEPROP 1 LAST PART_NUMBER E15431-004
J 0
(2000 -800);
DISPLAY 0.617021 (2000 -800);
PAINT BLUE (2000 -800);
FORCEPROP 1 LAST LOCATION C5G16
J 0
(2000 -550);
DISPLAY 0.617021 (2000 -550);
PAINT AQUA (2000 -550);
FORCEPROP 1 LASTPIN (1950 -750) $PN 2
J 0
(1960 -770);
DISPLAY 0.787234 (1960 -770);
PAINT ORANGE (1960 -770);
DISPLAY INVISIBLE (1960 -770);
FORCEPROP 1 LASTPIN (1950 -550) $PN 1
J 0
(1960 -570);
DISPLAY 0.787234 (1960 -570);
PAINT ORANGE (1960 -570);
DISPLAY INVISIBLE (1960 -570);
FORCEPROP 2 LAST CDS_LIB dev_discrete
J 0
(1950 -650);
PAINT ORANGE (1950 -650);
DISPLAY INVISIBLE (1950 -650);
FORCEPROP 2 LAST CDS_LOCATION C5G16
J 0
(2000 -550);
DISPLAY 0.617021 (2000 -550);
PAINT AQUA (2000 -550);
DISPLAY INVISIBLE (2000 -550);
FORCEPROP 0 LAST ROOM PVDDQ_ABC
J 0
(2000 -450);
DISPLAY 1.021277 (2000 -450);
PAINT ORANGE (2000 -450);
DISPLAY INVISIBLE (2000 -450);
FORCEPROP 1 LAST PATH I221
J 0
(2000 -500);
DISPLAY 0.978723 (2000 -500);
PAINT WHITE (2000 -500);
DISPLAY INVISIBLE (2000 -500);
FORCEPROP 2 LAST $SEC 1
J 0
(2000 -450);
PAINT MONO (2000 -450);
DISPLAY INVISIBLE (2000 -450);
FORCEPROP 2 LAST CDS_SEC 1
J 0
(2000 -450);
PAINT MONO (2000 -450);
DISPLAY INVISIBLE (2000 -450);
FORCEADD CAP_A..1
(1675 50);
FORCEPROP 1 LAST PART_NUMBER E15431-004
J 0
(1725 -100);
DISPLAY 0.617021 (1725 -100);
PAINT BLUE (1725 -100);
FORCEPROP 1 LAST PACK_TYPE 0603V
J 0
(1725 -150);
DISPLAY 0.617021 (1725 -150);
PAINT SKYBLUE (1725 -150);
FORCEPROP 1 LAST MATERIAL X6S
J 0
(1725 -50);
DISPLAY 0.617021 (1725 -50);
PAINT SKYBLUE (1725 -50);
FORCEPROP 1 LAST TOLERANCE 20%
J 0
(1725 0);
DISPLAY 0.617021 (1725 0);
PAINT SKYBLUE (1725 0);
FORCEPROP 1 LAST VOLTAGE 4V
J 0
(1725 50);
DISPLAY 0.617021 (1725 50);
PAINT SKYBLUE (1725 50);
FORCEPROP 1 LAST VALUE 22.0UF
J 0
(1725 100);
DISPLAY 0.617021 (1725 100);
PAINT SKYBLUE (1725 100);
FORCEPROP 1 LAST LOCATION C5T8
J 0
(1725 150);
DISPLAY 0.617021 (1725 150);
PAINT AQUA (1725 150);
FORCEPROP 1 LASTPIN (1675 -50) $PN 2
J 0
(1685 -70);
DISPLAY 0.787234 (1685 -70);
PAINT ORANGE (1685 -70);
DISPLAY INVISIBLE (1685 -70);
FORCEPROP 2 LAST CDS_LOCATION C5T8
J 0
(1725 150);
DISPLAY 0.617021 (1725 150);
PAINT AQUA (1725 150);
DISPLAY INVISIBLE (1725 150);
FORCEPROP 2 LAST CDS_LIB dev_discrete
J 0
(1675 50);
PAINT ORANGE (1675 50);
DISPLAY INVISIBLE (1675 50);
FORCEPROP 1 LAST PATH I222
J 0
(1725 200);
DISPLAY 0.978723 (1725 200);
PAINT WHITE (1725 200);
DISPLAY INVISIBLE (1725 200);
FORCEPROP 1 LASTPIN (1675 150) $PN 1
J 0
(1685 130);
DISPLAY 0.787234 (1685 130);
PAINT ORANGE (1685 130);
DISPLAY INVISIBLE (1685 130);
FORCEPROP 0 LAST ROOM PVDDQ_ABC
J 0
(1725 250);
DISPLAY 1.021277 (1725 250);
PAINT ORANGE (1725 250);
DISPLAY INVISIBLE (1725 250);
FORCEPROP 2 LAST $SEC 1
J 0
(1725 250);
PAINT MONO (1725 250);
DISPLAY INVISIBLE (1725 250);
FORCEPROP 2 LAST CDS_SEC 1
J 0
(1725 250);
PAINT MONO (1725 250);
DISPLAY INVISIBLE (1725 250);
FORCEADD CAP_A..1
(1650 -650);
FORCEPROP 1 LASTPIN (1650 -750) $PN 2
J 0
(1660 -770);
DISPLAY 0.617021 (1660 -770);
PAINT ORANGE (1660 -770);
FORCEPROP 1 LAST TOLERANCE 20%
J 0
(1700 -700);
DISPLAY 0.617021 (1700 -700);
PAINT SKYBLUE (1700 -700);
FORCEPROP 1 LAST VOLTAGE 4V
J 0
(1700 -650);
DISPLAY 0.617021 (1700 -650);
PAINT SKYBLUE (1700 -650);
FORCEPROP 1 LAST MATERIAL X6S
J 0
(1700 -750);
DISPLAY 0.617021 (1700 -750);
PAINT SKYBLUE (1700 -750);
FORCEPROP 1 LASTPIN (1650 -550) $PN 1
J 0
(1660 -570);
DISPLAY 0.617021 (1660 -570);
PAINT ORANGE (1660 -570);
FORCEPROP 1 LAST PACK_TYPE 0603V
J 0
(1700 -850);
DISPLAY 0.617021 (1700 -850);
PAINT SKYBLUE (1700 -850);
FORCEPROP 1 LAST VALUE 22.0UF
J 0
(1700 -600);
DISPLAY 0.617021 (1700 -600);
PAINT SKYBLUE (1700 -600);
FORCEPROP 1 LAST PART_NUMBER E15431-004
J 0
(1700 -800);
DISPLAY 0.617021 (1700 -800);
PAINT BLUE (1700 -800);
FORCEPROP 1 LAST LOCATION C5G14
J 0
(1700 -550);
DISPLAY 0.617021 (1700 -550);
PAINT AQUA (1700 -550);
FORCEPROP 2 LAST CDS_LIB dev_discrete
J 0
(1650 -650);
PAINT ORANGE (1650 -650);
DISPLAY INVISIBLE (1650 -650);
FORCEPROP 2 LAST CDS_LOCATION C5G14
J 0
(1700 -550);
DISPLAY 0.617021 (1700 -550);
PAINT AQUA (1700 -550);
DISPLAY INVISIBLE (1700 -550);
FORCEPROP 2 LAST CDS_SEC 1
J 0
(1700 -500);
PAINT ORANGE (1700 -500);
DISPLAY INVISIBLE (1700 -500);
FORCEPROP 2 LAST SEC_TYPE 0603V
J 0
(1700 -450);
DISPLAY 1.021277 (1700 -450);
PAINT ORANGE (1700 -450);
DISPLAY INVISIBLE (1700 -450);
FORCEPROP 2 LAST SEC 1
J 0
(1700 -450);
DISPLAY 0.680851 (1700 -450);
PAINT MONO (1700 -450);
DISPLAY INVISIBLE (1700 -450);
FORCEPROP 1 LAST PATH I223
J 0
(1700 -500);
DISPLAY 0.978723 (1700 -500);
PAINT WHITE (1700 -500);
DISPLAY INVISIBLE (1700 -500);
FORCEPROP 0 LAST ROOM PVDDQ_ABC
J 0
(1700 -450);
DISPLAY 1.021277 (1700 -450);
PAINT ORANGE (1700 -450);
DISPLAY INVISIBLE (1700 -450);
FORCEADD CAP_A..1
(1400 50);
FORCEPROP 1 LAST MATERIAL X6S
J 0
(1450 -50);
DISPLAY 0.617021 (1450 -50);
PAINT SKYBLUE (1450 -50);
FORCEPROP 1 LAST PACK_TYPE 0603V
J 0
(1450 -150);
DISPLAY 0.617021 (1450 -150);
PAINT SKYBLUE (1450 -150);
FORCEPROP 1 LAST PART_NUMBER E15431-004
J 0
(1450 -100);
DISPLAY 0.617021 (1450 -100);
PAINT BLUE (1450 -100);
FORCEPROP 1 LAST TOLERANCE 20%
J 0
(1450 0);
DISPLAY 0.617021 (1450 0);
PAINT SKYBLUE (1450 0);
FORCEPROP 1 LAST VOLTAGE 4V
J 0
(1450 50);
DISPLAY 0.617021 (1450 50);
PAINT SKYBLUE (1450 50);
FORCEPROP 1 LAST VALUE 22.0UF
J 0
(1450 100);
DISPLAY 0.617021 (1450 100);
PAINT SKYBLUE (1450 100);
FORCEPROP 1 LAST LOCATION C5T9
J 0
(1450 150);
DISPLAY 0.617021 (1450 150);
PAINT AQUA (1450 150);
FORCEPROP 1 LASTPIN (1400 -50) $PN 2
J 0
(1410 -70);
DISPLAY 0.787234 (1410 -70);
PAINT ORANGE (1410 -70);
DISPLAY INVISIBLE (1410 -70);
FORCEPROP 2 LAST CDS_LIB dev_discrete
J 0
(1400 50);
PAINT ORANGE (1400 50);
DISPLAY INVISIBLE (1400 50);
FORCEPROP 2 LAST CDS_LOCATION C5T9
J 0
(1450 150);
DISPLAY 0.617021 (1450 150);
PAINT AQUA (1450 150);
DISPLAY INVISIBLE (1450 150);
FORCEPROP 1 LAST PATH I224
J 0
(1450 200);
DISPLAY 0.978723 (1450 200);
PAINT WHITE (1450 200);
DISPLAY INVISIBLE (1450 200);
FORCEPROP 1 LASTPIN (1400 150) $PN 1
J 0
(1410 130);
DISPLAY 0.787234 (1410 130);
PAINT ORANGE (1410 130);
DISPLAY INVISIBLE (1410 130);
FORCEPROP 0 LAST ROOM PVDDQ_ABC
J 0
(1450 250);
DISPLAY 1.021277 (1450 250);
PAINT ORANGE (1450 250);
DISPLAY INVISIBLE (1450 250);
FORCEPROP 2 LAST $SEC 1
J 0
(1450 250);
PAINT MONO (1450 250);
DISPLAY INVISIBLE (1450 250);
FORCEPROP 2 LAST CDS_SEC 1
J 0
(1450 250);
PAINT MONO (1450 250);
DISPLAY INVISIBLE (1450 250);
FORCEADD CAP_A..1
(1125 50);
FORCEPROP 1 LAST MATERIAL X6S
J 0
(1175 -50);
DISPLAY 0.617021 (1175 -50);
PAINT SKYBLUE (1175 -50);
FORCEPROP 1 LAST PART_NUMBER E15431-004
J 0
(1175 -100);
DISPLAY 0.617021 (1175 -100);
PAINT BLUE (1175 -100);
FORCEPROP 1 LAST PACK_TYPE 0603V
J 0
(1175 -150);
DISPLAY 0.617021 (1175 -150);
PAINT SKYBLUE (1175 -150);
FORCEPROP 1 LAST TOLERANCE 20%
J 0
(1175 0);
DISPLAY 0.617021 (1175 0);
PAINT SKYBLUE (1175 0);
FORCEPROP 1 LAST VOLTAGE 4V
J 0
(1175 50);
DISPLAY 0.617021 (1175 50);
PAINT SKYBLUE (1175 50);
FORCEPROP 1 LAST VALUE 22.0UF
J 0
(1175 100);
DISPLAY 0.617021 (1175 100);
PAINT SKYBLUE (1175 100);
FORCEPROP 1 LAST LOCATION C5T10
J 0
(1175 150);
DISPLAY 0.617021 (1175 150);
PAINT AQUA (1175 150);
FORCEPROP 1 LASTPIN (1125 -50) $PN 2
J 0
(1135 -70);
DISPLAY 0.787234 (1135 -70);
PAINT ORANGE (1135 -70);
DISPLAY INVISIBLE (1135 -70);
FORCEPROP 2 LAST CDS_LIB dev_discrete
J 0
(1125 50);
PAINT ORANGE (1125 50);
DISPLAY INVISIBLE (1125 50);
FORCEPROP 1 LASTPIN (1125 150) $PN 1
J 0
(1135 130);
DISPLAY 0.787234 (1135 130);
PAINT ORANGE (1135 130);
DISPLAY INVISIBLE (1135 130);
FORCEPROP 2 LAST CDS_LOCATION C5T10
J 0
(1175 150);
DISPLAY 0.617021 (1175 150);
PAINT AQUA (1175 150);
DISPLAY INVISIBLE (1175 150);
FORCEPROP 1 LAST PATH I225
J 0
(1175 200);
DISPLAY 0.978723 (1175 200);
PAINT WHITE (1175 200);
DISPLAY INVISIBLE (1175 200);
FORCEPROP 0 LAST ROOM PVDDQ_ABC
J 0
(1175 250);
DISPLAY 1.021277 (1175 250);
PAINT ORANGE (1175 250);
DISPLAY INVISIBLE (1175 250);
FORCEPROP 2 LAST $SEC 1
J 0
(1175 250);
PAINT MONO (1175 250);
DISPLAY INVISIBLE (1175 250);
FORCEPROP 2 LAST CDS_SEC 1
J 0
(1175 250);
PAINT MONO (1175 250);
DISPLAY INVISIBLE (1175 250);
FORCEADD CAP_A..1
(1375 -650);
FORCEPROP 1 LAST TOLERANCE 20%
J 0
(1425 -700);
DISPLAY 0.617021 (1425 -700);
PAINT SKYBLUE (1425 -700);
FORCEPROP 1 LAST VOLTAGE 4V
J 0
(1425 -650);
DISPLAY 0.617021 (1425 -650);
PAINT SKYBLUE (1425 -650);
FORCEPROP 1 LAST MATERIAL X6S
J 0
(1425 -750);
DISPLAY 0.617021 (1425 -750);
PAINT SKYBLUE (1425 -750);
FORCEPROP 1 LAST PACK_TYPE 0603V
J 0
(1425 -850);
DISPLAY 0.617021 (1425 -850);
PAINT SKYBLUE (1425 -850);
FORCEPROP 1 LAST VALUE 22.0UF
J 0
(1425 -600);
DISPLAY 0.617021 (1425 -600);
PAINT SKYBLUE (1425 -600);
FORCEPROP 1 LAST PART_NUMBER E15431-004
J 0
(1425 -800);
DISPLAY 0.617021 (1425 -800);
PAINT BLUE (1425 -800);
FORCEPROP 1 LAST LOCATION C5G17
J 0
(1425 -550);
DISPLAY 0.617021 (1425 -550);
PAINT AQUA (1425 -550);
FORCEPROP 1 LASTPIN (1375 -750) $PN 2
J 0
(1385 -770);
DISPLAY 0.787234 (1385 -770);
PAINT ORANGE (1385 -770);
DISPLAY INVISIBLE (1385 -770);
FORCEPROP 1 LASTPIN (1375 -550) $PN 1
J 0
(1385 -570);
DISPLAY 0.787234 (1385 -570);
PAINT ORANGE (1385 -570);
DISPLAY INVISIBLE (1385 -570);
FORCEPROP 2 LAST CDS_LIB dev_discrete
J 0
(1375 -650);
PAINT ORANGE (1375 -650);
DISPLAY INVISIBLE (1375 -650);
FORCEPROP 2 LAST CDS_LOCATION C5G17
J 0
(1425 -550);
DISPLAY 0.617021 (1425 -550);
PAINT AQUA (1425 -550);
DISPLAY INVISIBLE (1425 -550);
FORCEPROP 2 LAST CDS_SEC 1
J 0
(1425 -450);
PAINT MONO (1425 -450);
DISPLAY INVISIBLE (1425 -450);
FORCEPROP 2 LAST $SEC 1
J 0
(1425 -450);
PAINT MONO (1425 -450);
DISPLAY INVISIBLE (1425 -450);
FORCEPROP 1 LAST PATH I226
J 0
(1425 -500);
DISPLAY 0.978723 (1425 -500);
PAINT WHITE (1425 -500);
DISPLAY INVISIBLE (1425 -500);
FORCEPROP 0 LAST ROOM PVDDQ_ABC
J 0
(1425 -450);
DISPLAY 1.021277 (1425 -450);
PAINT ORANGE (1425 -450);
DISPLAY INVISIBLE (1425 -450);
FORCEADD CAP_A..1
(1100 -650);
FORCEPROP 1 LAST TOLERANCE 20%
J 0
(1150 -700);
DISPLAY 0.617021 (1150 -700);
PAINT SKYBLUE (1150 -700);
FORCEPROP 1 LAST VOLTAGE 4V
J 0
(1150 -650);
DISPLAY 0.617021 (1150 -650);
PAINT SKYBLUE (1150 -650);
FORCEPROP 1 LAST MATERIAL X6S
J 0
(1150 -750);
DISPLAY 0.617021 (1150 -750);
PAINT SKYBLUE (1150 -750);
FORCEPROP 1 LAST PACK_TYPE 0603V
J 0
(1150 -850);
DISPLAY 0.617021 (1150 -850);
PAINT SKYBLUE (1150 -850);
FORCEPROP 1 LAST VALUE 22.0UF
J 0
(1150 -600);
DISPLAY 0.617021 (1150 -600);
PAINT SKYBLUE (1150 -600);
FORCEPROP 1 LAST PART_NUMBER E15431-004
J 0
(1150 -800);
DISPLAY 0.617021 (1150 -800);
PAINT BLUE (1150 -800);
FORCEPROP 1 LAST LOCATION C5G18
J 0
(1150 -550);
DISPLAY 0.617021 (1150 -550);
PAINT AQUA (1150 -550);
FORCEPROP 1 LASTPIN (1100 -750) $PN 2
J 0
(1110 -770);
DISPLAY 0.787234 (1110 -770);
PAINT ORANGE (1110 -770);
DISPLAY INVISIBLE (1110 -770);
FORCEPROP 1 LASTPIN (1100 -550) $PN 1
J 0
(1110 -570);
DISPLAY 0.787234 (1110 -570);
PAINT ORANGE (1110 -570);
DISPLAY INVISIBLE (1110 -570);
FORCEPROP 2 LAST CDS_LIB dev_discrete
J 0
(1100 -650);
PAINT ORANGE (1100 -650);
DISPLAY INVISIBLE (1100 -650);
FORCEPROP 2 LAST CDS_LOCATION C5G18
J 0
(1150 -550);
DISPLAY 0.617021 (1150 -550);
PAINT AQUA (1150 -550);
DISPLAY INVISIBLE (1150 -550);
FORCEPROP 2 LAST CDS_SEC 1
J 0
(1150 -450);
PAINT MONO (1150 -450);
DISPLAY INVISIBLE (1150 -450);
FORCEPROP 2 LAST $SEC 1
J 0
(1150 -450);
PAINT MONO (1150 -450);
DISPLAY INVISIBLE (1150 -450);
FORCEPROP 1 LAST PATH I227
J 0
(1150 -500);
DISPLAY 0.978723 (1150 -500);
PAINT WHITE (1150 -500);
DISPLAY INVISIBLE (1150 -500);
FORCEPROP 0 LAST ROOM PVDDQ_ABC
J 0
(1150 -450);
DISPLAY 1.021277 (1150 -450);
PAINT ORANGE (1150 -450);
DISPLAY INVISIBLE (1150 -450);
FORCEADD CAP_A..1
(825 50);
FORCEPROP 1 LAST PACK_TYPE 0603V
J 0
(875 -150);
DISPLAY 0.617021 (875 -150);
PAINT SKYBLUE (875 -150);
FORCEPROP 1 LAST MATERIAL X6S
J 0
(875 -50);
DISPLAY 0.617021 (875 -50);
PAINT SKYBLUE (875 -50);
FORCEPROP 1 LAST PART_NUMBER E15431-004
J 0
(875 -100);
DISPLAY 0.617021 (875 -100);
PAINT BLUE (875 -100);
FORCEPROP 1 LAST TOLERANCE 20%
J 0
(875 0);
DISPLAY 0.617021 (875 0);
PAINT SKYBLUE (875 0);
FORCEPROP 1 LAST VOLTAGE 4V
J 0
(875 50);
DISPLAY 0.617021 (875 50);
PAINT SKYBLUE (875 50);
FORCEPROP 1 LAST LOCATION C5T11
J 0
(875 150);
DISPLAY 0.617021 (875 150);
PAINT AQUA (875 150);
FORCEPROP 1 LAST VALUE 22.0UF
J 0
(875 100);
DISPLAY 0.617021 (875 100);
PAINT SKYBLUE (875 100);
FORCEPROP 1 LASTPIN (825 -50) $PN 2
J 0
(835 -70);
DISPLAY 0.787234 (835 -70);
PAINT ORANGE (835 -70);
DISPLAY INVISIBLE (835 -70);
FORCEPROP 2 LAST CDS_LIB dev_discrete
J 0
(825 50);
PAINT ORANGE (825 50);
DISPLAY INVISIBLE (825 50);
FORCEPROP 1 LASTPIN (825 150) $PN 1
J 0
(835 130);
DISPLAY 0.787234 (835 130);
PAINT ORANGE (835 130);
DISPLAY INVISIBLE (835 130);
FORCEPROP 1 LAST PATH I228
J 0
(875 200);
DISPLAY 0.978723 (875 200);
PAINT WHITE (875 200);
DISPLAY INVISIBLE (875 200);
FORCEPROP 2 LAST CDS_LOCATION C5T11
J 0
(875 150);
DISPLAY 0.617021 (875 150);
PAINT AQUA (875 150);
DISPLAY INVISIBLE (875 150);
FORCEPROP 0 LAST ROOM PVDDQ_ABC
J 0
(875 250);
DISPLAY 1.021277 (875 250);
PAINT ORANGE (875 250);
DISPLAY INVISIBLE (875 250);
FORCEPROP 2 LAST $SEC 1
J 0
(875 250);
PAINT MONO (875 250);
DISPLAY INVISIBLE (875 250);
FORCEPROP 2 LAST CDS_SEC 1
J 0
(875 250);
PAINT MONO (875 250);
DISPLAY INVISIBLE (875 250);
FORCEADD CAP_A..1
(525 50);
FORCEPROP 1 LAST PACK_TYPE 0603V
J 0
(575 -150);
DISPLAY 0.617021 (575 -150);
PAINT SKYBLUE (575 -150);
FORCEPROP 1 LAST MATERIAL X6S
J 0
(575 -50);
DISPLAY 0.617021 (575 -50);
PAINT SKYBLUE (575 -50);
FORCEPROP 1 LAST PART_NUMBER E15431-004
J 0
(575 -100);
DISPLAY 0.617021 (575 -100);
PAINT BLUE (575 -100);
FORCEPROP 1 LAST TOLERANCE 20%
J 0
(575 0);
DISPLAY 0.617021 (575 0);
PAINT SKYBLUE (575 0);
FORCEPROP 1 LAST VOLTAGE 4V
J 0
(575 50);
DISPLAY 0.617021 (575 50);
PAINT SKYBLUE (575 50);
FORCEPROP 1 LAST VALUE 22.0UF
J 0
(575 100);
DISPLAY 0.617021 (575 100);
PAINT SKYBLUE (575 100);
FORCEPROP 1 LAST LOCATION C5T12
J 0
(575 150);
DISPLAY 0.617021 (575 150);
PAINT AQUA (575 150);
FORCEPROP 1 LASTPIN (525 -50) $PN 2
J 0
(535 -70);
DISPLAY 0.787234 (535 -70);
PAINT ORANGE (535 -70);
DISPLAY INVISIBLE (535 -70);
FORCEPROP 2 LAST CDS_LOCATION C5T12
J 0
(575 150);
DISPLAY 0.617021 (575 150);
PAINT AQUA (575 150);
DISPLAY INVISIBLE (575 150);
FORCEPROP 2 LAST CDS_LIB dev_discrete
J 0
(525 50);
PAINT ORANGE (525 50);
DISPLAY INVISIBLE (525 50);
FORCEPROP 1 LAST PATH I229
J 0
(575 200);
DISPLAY 0.978723 (575 200);
PAINT WHITE (575 200);
DISPLAY INVISIBLE (575 200);
FORCEPROP 1 LASTPIN (525 150) $PN 1
J 0
(535 130);
DISPLAY 0.787234 (535 130);
PAINT ORANGE (535 130);
DISPLAY INVISIBLE (535 130);
FORCEPROP 0 LAST ROOM PVDDQ_ABC
J 0
(575 250);
DISPLAY 1.021277 (575 250);
PAINT ORANGE (575 250);
DISPLAY INVISIBLE (575 250);
FORCEPROP 2 LAST $SEC 1
J 0
(575 250);
PAINT MONO (575 250);
DISPLAY INVISIBLE (575 250);
FORCEPROP 2 LAST CDS_SEC 1
J 0
(575 250);
PAINT MONO (575 250);
DISPLAY INVISIBLE (575 250);
FORCEADD CAP_A..1
(800 -650);
FORCEPROP 1 LAST PACK_TYPE 0603V
J 0
(850 -850);
DISPLAY 0.617021 (850 -850);
PAINT SKYBLUE (850 -850);
FORCEPROP 1 LAST LOCATION C5G8
J 0
(850 -550);
DISPLAY 0.617021 (850 -550);
PAINT AQUA (850 -550);
FORCEPROP 1 LAST TOLERANCE 20%
J 0
(850 -700);
DISPLAY 0.617021 (850 -700);
PAINT SKYBLUE (850 -700);
FORCEPROP 1 LAST VOLTAGE 4V
J 0
(850 -650);
DISPLAY 0.617021 (850 -650);
PAINT SKYBLUE (850 -650);
FORCEPROP 1 LAST MATERIAL X6S
J 0
(850 -750);
DISPLAY 0.617021 (850 -750);
PAINT SKYBLUE (850 -750);
FORCEPROP 1 LAST VALUE 22.0UF
J 0
(850 -600);
DISPLAY 0.617021 (850 -600);
PAINT SKYBLUE (850 -600);
FORCEPROP 1 LAST PART_NUMBER E15431-004
J 0
(850 -800);
DISPLAY 0.617021 (850 -800);
PAINT BLUE (850 -800);
FORCEPROP 1 LASTPIN (800 -750) $PN 2
J 0
(810 -770);
DISPLAY 0.787234 (810 -770);
PAINT ORANGE (810 -770);
DISPLAY INVISIBLE (810 -770);
FORCEPROP 1 LASTPIN (800 -550) $PN 1
J 0
(810 -570);
DISPLAY 0.787234 (810 -570);
PAINT ORANGE (810 -570);
DISPLAY INVISIBLE (810 -570);
FORCEPROP 2 LAST CDS_LIB dev_discrete
J 0
(800 -650);
PAINT ORANGE (800 -650);
DISPLAY INVISIBLE (800 -650);
FORCEPROP 2 LAST CDS_LOCATION C5G8
J 0
(850 -550);
DISPLAY 0.617021 (850 -550);
PAINT AQUA (850 -550);
DISPLAY INVISIBLE (850 -550);
FORCEPROP 2 LAST CDS_SEC 1
J 0
(850 -450);
PAINT MONO (850 -450);
DISPLAY INVISIBLE (850 -450);
FORCEPROP 2 LAST $SEC 1
J 0
(850 -450);
PAINT MONO (850 -450);
DISPLAY INVISIBLE (850 -450);
FORCEPROP 1 LAST PATH I230
J 0
(850 -500);
DISPLAY 0.978723 (850 -500);
PAINT WHITE (850 -500);
DISPLAY INVISIBLE (850 -500);
FORCEPROP 0 LAST ROOM PVDDQ_ABC
J 0
(850 -450);
DISPLAY 1.021277 (850 -450);
PAINT ORANGE (850 -450);
DISPLAY INVISIBLE (850 -450);
FORCEADD CAP_A..1
(500 -650);
FORCEPROP 1 LASTPIN (500 -550) $PN 1
J 0
(510 -570);
DISPLAY 0.617021 (510 -570);
PAINT ORANGE (510 -570);
FORCEPROP 1 LASTPIN (500 -750) $PN 2
J 0
(510 -770);
DISPLAY 0.617021 (510 -770);
PAINT ORANGE (510 -770);
FORCEPROP 1 LAST LOCATION C5G1
J 0
(550 -550);
DISPLAY 0.617021 (550 -550);
PAINT AQUA (550 -550);
FORCEPROP 1 LAST VALUE 22.0UF
J 0
(550 -600);
DISPLAY 0.617021 (550 -600);
PAINT SKYBLUE (550 -600);
FORCEPROP 1 LAST TOLERANCE 20%
J 0
(550 -700);
DISPLAY 0.617021 (550 -700);
PAINT SKYBLUE (550 -700);
FORCEPROP 1 LAST MATERIAL X6S
J 0
(550 -750);
DISPLAY 0.617021 (550 -750);
PAINT SKYBLUE (550 -750);
FORCEPROP 1 LAST VOLTAGE 4V
J 0
(550 -650);
DISPLAY 0.617021 (550 -650);
PAINT SKYBLUE (550 -650);
FORCEPROP 1 LAST PACK_TYPE 0603V
J 0
(550 -850);
DISPLAY 0.617021 (550 -850);
PAINT SKYBLUE (550 -850);
FORCEPROP 1 LAST PART_NUMBER E15431-004
J 0
(550 -800);
DISPLAY 0.617021 (550 -800);
PAINT BLUE (550 -800);
FORCEPROP 2 LAST CDS_LIB dev_discrete
J 0
(500 -650);
PAINT ORANGE (500 -650);
DISPLAY INVISIBLE (500 -650);
FORCEPROP 2 LAST CDS_LOCATION C5G1
J 0
(550 -550);
DISPLAY 0.617021 (550 -550);
PAINT AQUA (550 -550);
DISPLAY INVISIBLE (550 -550);
FORCEPROP 0 LAST ROOM PVDDQ_ABC
J 0
(550 -450);
DISPLAY 1.021277 (550 -450);
PAINT ORANGE (550 -450);
DISPLAY INVISIBLE (550 -450);
FORCEPROP 2 LAST CDS_SEC 1
J 0
(550 -500);
PAINT ORANGE (550 -500);
DISPLAY INVISIBLE (550 -500);
FORCEPROP 1 LAST PATH I231
J 0
(550 -500);
DISPLAY 0.978723 (550 -500);
PAINT WHITE (550 -500);
DISPLAY INVISIBLE (550 -500);
FORCEPROP 2 LAST SEC_TYPE 0603V
J 0
(550 -450);
DISPLAY 1.021277 (550 -450);
PAINT ORANGE (550 -450);
DISPLAY INVISIBLE (550 -450);
FORCEPROP 2 LAST SEC 1
J 0
(550 -450);
DISPLAY 0.680851 (550 -450);
PAINT MONO (550 -450);
DISPLAY INVISIBLE (550 -450);
FORCEADD CAP_A..1
(200 50);
FORCEPROP 1 LAST PACK_TYPE 0603V
J 0
(250 -150);
DISPLAY 0.617021 (250 -150);
PAINT SKYBLUE (250 -150);
FORCEPROP 1 LAST MATERIAL X6S
J 0
(250 -50);
DISPLAY 0.617021 (250 -50);
PAINT SKYBLUE (250 -50);
FORCEPROP 1 LAST PART_NUMBER E15431-004
J 0
(250 -100);
DISPLAY 0.617021 (250 -100);
PAINT BLUE (250 -100);
FORCEPROP 1 LAST TOLERANCE 20%
J 0
(250 0);
DISPLAY 0.617021 (250 0);
PAINT SKYBLUE (250 0);
FORCEPROP 1 LAST LOCATION C5U9
J 0
(250 150);
DISPLAY 0.617021 (250 150);
PAINT AQUA (250 150);
FORCEPROP 1 LAST VALUE 22.0UF
J 0
(250 100);
DISPLAY 0.617021 (250 100);
PAINT SKYBLUE (250 100);
FORCEPROP 1 LAST VOLTAGE 4V
J 0
(250 50);
DISPLAY 0.617021 (250 50);
PAINT SKYBLUE (250 50);
FORCEPROP 1 LASTPIN (200 -50) $PN 2
J 0
(210 -70);
DISPLAY 0.787234 (210 -70);
PAINT ORANGE (210 -70);
DISPLAY INVISIBLE (210 -70);
FORCEPROP 2 LAST CDS_LIB dev_discrete
J 0
(200 50);
PAINT ORANGE (200 50);
DISPLAY INVISIBLE (200 50);
FORCEPROP 1 LASTPIN (200 150) $PN 1
J 0
(210 130);
DISPLAY 0.787234 (210 130);
PAINT ORANGE (210 130);
DISPLAY INVISIBLE (210 130);
FORCEPROP 1 LAST PATH I232
J 0
(250 200);
DISPLAY 0.978723 (250 200);
PAINT WHITE (250 200);
DISPLAY INVISIBLE (250 200);
FORCEPROP 2 LAST CDS_LOCATION C5U9
J 0
(250 150);
DISPLAY 0.617021 (250 150);
PAINT AQUA (250 150);
DISPLAY INVISIBLE (250 150);
FORCEPROP 0 LAST ROOM PVDDQ_ABC
J 0
(250 250);
DISPLAY 1.021277 (250 250);
PAINT ORANGE (250 250);
DISPLAY INVISIBLE (250 250);
FORCEPROP 2 LAST CDS_SEC 1
J 0
(250 250);
PAINT MONO (250 250);
DISPLAY INVISIBLE (250 250);
FORCEPROP 2 LAST $SEC 1
J 0
(250 250);
PAINT MONO (250 250);
DISPLAY INVISIBLE (250 250);
FORCEADD CAP_A..1
(-75 50);
FORCEPROP 1 LAST MATERIAL X6S
J 0
(-25 -50);
DISPLAY 0.617021 (-25 -50);
PAINT SKYBLUE (-25 -50);
FORCEPROP 1 LAST VOLTAGE 4V
J 0
(-25 50);
DISPLAY 0.617021 (-25 50);
PAINT SKYBLUE (-25 50);
FORCEPROP 1 LAST PACK_TYPE 0603V
J 0
(-25 -150);
DISPLAY 0.617021 (-25 -150);
PAINT SKYBLUE (-25 -150);
FORCEPROP 1 LAST TOLERANCE 20%
J 0
(-25 0);
DISPLAY 0.617021 (-25 0);
PAINT SKYBLUE (-25 0);
FORCEPROP 1 LAST VALUE 22.0UF
J 0
(-25 100);
DISPLAY 0.617021 (-25 100);
PAINT SKYBLUE (-25 100);
FORCEPROP 1 LAST PART_NUMBER E15431-004
J 0
(-25 -100);
DISPLAY 0.617021 (-25 -100);
PAINT BLUE (-25 -100);
FORCEPROP 1 LAST LOCATION C5U8
J 0
(-25 150);
DISPLAY 0.617021 (-25 150);
PAINT AQUA (-25 150);
FORCEPROP 1 LASTPIN (-75 -50) $PN 2
J 0
(-65 -70);
DISPLAY 0.787234 (-65 -70);
PAINT ORANGE (-65 -70);
DISPLAY INVISIBLE (-65 -70);
FORCEPROP 2 LAST CDS_LIB dev_discrete
J 0
(-75 50);
PAINT ORANGE (-75 50);
DISPLAY INVISIBLE (-75 50);
FORCEPROP 1 LASTPIN (-75 150) $PN 1
J 0
(-65 130);
DISPLAY 0.787234 (-65 130);
PAINT ORANGE (-65 130);
DISPLAY INVISIBLE (-65 130);
FORCEPROP 1 LAST PATH I233
J 0
(-25 200);
DISPLAY 0.978723 (-25 200);
PAINT WHITE (-25 200);
DISPLAY INVISIBLE (-25 200);
FORCEPROP 2 LAST CDS_LOCATION C5U8
J 0
(-25 150);
DISPLAY 0.617021 (-25 150);
PAINT AQUA (-25 150);
DISPLAY INVISIBLE (-25 150);
FORCEPROP 0 LAST ROOM PVDDQ_ABC
J 0
(-25 250);
DISPLAY 1.021277 (-25 250);
PAINT ORANGE (-25 250);
DISPLAY INVISIBLE (-25 250);
FORCEPROP 2 LAST $SEC 1
J 0
(-25 250);
PAINT MONO (-25 250);
DISPLAY INVISIBLE (-25 250);
FORCEPROP 2 LAST CDS_SEC 1
J 0
(-25 250);
PAINT MONO (-25 250);
DISPLAY INVISIBLE (-25 250);
FORCEADD CAP_A..1
(175 -650);
FORCEPROP 1 LAST VOLTAGE 4V
J 0
(225 -650);
DISPLAY 0.617021 (225 -650);
PAINT SKYBLUE (225 -650);
FORCEPROP 1 LAST MATERIAL X6S
J 0
(225 -750);
DISPLAY 0.617021 (225 -750);
PAINT SKYBLUE (225 -750);
FORCEPROP 1 LAST PACK_TYPE 0603V
J 0
(225 -850);
DISPLAY 0.617021 (225 -850);
PAINT SKYBLUE (225 -850);
FORCEPROP 1 LAST TOLERANCE 20%
J 0
(225 -700);
DISPLAY 0.617021 (225 -700);
PAINT SKYBLUE (225 -700);
FORCEPROP 1 LAST VALUE 22.0UF
J 0
(225 -600);
DISPLAY 0.617021 (225 -600);
PAINT SKYBLUE (225 -600);
FORCEPROP 1 LAST LOCATION C5G7
J 0
(225 -550);
DISPLAY 0.617021 (225 -550);
PAINT AQUA (225 -550);
FORCEPROP 1 LAST PART_NUMBER E15431-004
J 0
(225 -800);
DISPLAY 0.617021 (225 -800);
PAINT BLUE (225 -800);
FORCEPROP 1 LASTPIN (175 -750) $PN 2
J 0
(185 -770);
DISPLAY 0.787234 (185 -770);
PAINT ORANGE (185 -770);
DISPLAY INVISIBLE (185 -770);
FORCEPROP 1 LASTPIN (175 -550) $PN 1
J 0
(185 -570);
DISPLAY 0.787234 (185 -570);
PAINT ORANGE (185 -570);
DISPLAY INVISIBLE (185 -570);
FORCEPROP 2 LAST CDS_LOCATION C5G7
J 0
(225 -550);
DISPLAY 0.617021 (225 -550);
PAINT AQUA (225 -550);
DISPLAY INVISIBLE (225 -550);
FORCEPROP 2 LAST CDS_LIB dev_discrete
J 0
(175 -650);
PAINT ORANGE (175 -650);
DISPLAY INVISIBLE (175 -650);
FORCEPROP 2 LAST CDS_SEC 1
J 0
(225 -450);
PAINT MONO (225 -450);
DISPLAY INVISIBLE (225 -450);
FORCEPROP 2 LAST $SEC 1
J 0
(225 -450);
PAINT MONO (225 -450);
DISPLAY INVISIBLE (225 -450);
FORCEPROP 1 LAST PATH I234
J 0
(225 -500);
DISPLAY 0.978723 (225 -500);
PAINT WHITE (225 -500);
DISPLAY INVISIBLE (225 -500);
FORCEPROP 0 LAST ROOM PVDDQ_ABC
J 0
(225 -450);
DISPLAY 1.021277 (225 -450);
PAINT ORANGE (225 -450);
DISPLAY INVISIBLE (225 -450);
FORCEADD CAP_A..1
(-100 -650);
FORCEPROP 1 LAST MATERIAL X6S
J 0
(-50 -750);
DISPLAY 0.617021 (-50 -750);
PAINT SKYBLUE (-50 -750);
FORCEPROP 1 LAST VOLTAGE 4V
J 0
(-50 -650);
DISPLAY 0.617021 (-50 -650);
PAINT SKYBLUE (-50 -650);
FORCEPROP 1 LAST PACK_TYPE 0603V
J 0
(-50 -850);
DISPLAY 0.617021 (-50 -850);
PAINT SKYBLUE (-50 -850);
FORCEPROP 1 LAST TOLERANCE 20%
J 0
(-50 -700);
DISPLAY 0.617021 (-50 -700);
PAINT SKYBLUE (-50 -700);
FORCEPROP 1 LAST VALUE 22.0UF
J 0
(-50 -600);
DISPLAY 0.617021 (-50 -600);
PAINT SKYBLUE (-50 -600);
FORCEPROP 1 LAST PART_NUMBER E15431-004
J 0
(-50 -800);
DISPLAY 0.617021 (-50 -800);
PAINT BLUE (-50 -800);
FORCEPROP 1 LAST LOCATION C5G5
J 0
(-50 -550);
DISPLAY 0.617021 (-50 -550);
PAINT AQUA (-50 -550);
FORCEPROP 1 LASTPIN (-100 -750) $PN 2
J 0
(-90 -770);
DISPLAY 0.787234 (-90 -770);
PAINT ORANGE (-90 -770);
DISPLAY INVISIBLE (-90 -770);
FORCEPROP 1 LASTPIN (-100 -550) $PN 1
J 0
(-90 -570);
DISPLAY 0.787234 (-90 -570);
PAINT ORANGE (-90 -570);
DISPLAY INVISIBLE (-90 -570);
FORCEPROP 2 LAST CDS_LIB dev_discrete
J 0
(-100 -650);
PAINT ORANGE (-100 -650);
DISPLAY INVISIBLE (-100 -650);
FORCEPROP 2 LAST CDS_LOCATION C5G5
J 0
(-50 -550);
DISPLAY 0.617021 (-50 -550);
PAINT AQUA (-50 -550);
DISPLAY INVISIBLE (-50 -550);
FORCEPROP 0 LAST ROOM PVDDQ_ABC
J 0
(-50 -450);
DISPLAY 1.021277 (-50 -450);
PAINT ORANGE (-50 -450);
DISPLAY INVISIBLE (-50 -450);
FORCEPROP 1 LAST PATH I235
J 0
(-50 -500);
DISPLAY 0.978723 (-50 -500);
PAINT WHITE (-50 -500);
DISPLAY INVISIBLE (-50 -500);
FORCEPROP 2 LAST CDS_SEC 1
J 0
(-50 -450);
PAINT MONO (-50 -450);
DISPLAY INVISIBLE (-50 -450);
FORCEPROP 2 LAST $SEC 1
J 0
(-50 -450);
PAINT MONO (-50 -450);
DISPLAY INVISIBLE (-50 -450);
FORCEADD CAP_A..1
(-375 50);
FORCEPROP 1 LAST PART_NUMBER E15431-004
J 0
(-325 -100);
DISPLAY 0.617021 (-325 -100);
PAINT BLUE (-325 -100);
FORCEPROP 1 LAST PACK_TYPE 0603V
J 0
(-325 -150);
DISPLAY 0.617021 (-325 -150);
PAINT SKYBLUE (-325 -150);
FORCEPROP 1 LAST MATERIAL X6S
J 0
(-325 -50);
DISPLAY 0.617021 (-325 -50);
PAINT SKYBLUE (-325 -50);
FORCEPROP 1 LAST TOLERANCE 20%
J 0
(-325 0);
DISPLAY 0.617021 (-325 0);
PAINT SKYBLUE (-325 0);
FORCEPROP 1 LAST VOLTAGE 4V
J 0
(-325 50);
DISPLAY 0.617021 (-325 50);
PAINT SKYBLUE (-325 50);
FORCEPROP 1 LAST LOCATION C5U7
J 0
(-325 150);
DISPLAY 0.617021 (-325 150);
PAINT AQUA (-325 150);
FORCEPROP 1 LAST VALUE 22.0UF
J 0
(-325 100);
DISPLAY 0.617021 (-325 100);
PAINT SKYBLUE (-325 100);
FORCEPROP 1 LASTPIN (-375 -50) $PN 2
J 0
(-365 -70);
DISPLAY 0.787234 (-365 -70);
PAINT ORANGE (-365 -70);
DISPLAY INVISIBLE (-365 -70);
FORCEPROP 2 LAST CDS_LOCATION C5U7
J 0
(-325 150);
DISPLAY 0.617021 (-325 150);
PAINT AQUA (-325 150);
DISPLAY INVISIBLE (-325 150);
FORCEPROP 2 LAST CDS_LIB dev_discrete
J 0
(-375 50);
PAINT ORANGE (-375 50);
DISPLAY INVISIBLE (-375 50);
FORCEPROP 1 LAST PATH I236
J 0
(-325 200);
DISPLAY 0.978723 (-325 200);
PAINT WHITE (-325 200);
DISPLAY INVISIBLE (-325 200);
FORCEPROP 1 LASTPIN (-375 150) $PN 1
J 0
(-365 130);
DISPLAY 0.787234 (-365 130);
PAINT ORANGE (-365 130);
DISPLAY INVISIBLE (-365 130);
FORCEPROP 0 LAST ROOM PVDDQ_ABC
J 0
(-325 250);
DISPLAY 1.021277 (-325 250);
PAINT ORANGE (-325 250);
DISPLAY INVISIBLE (-325 250);
FORCEPROP 2 LAST $SEC 1
J 0
(-325 250);
PAINT MONO (-325 250);
DISPLAY INVISIBLE (-325 250);
FORCEPROP 2 LAST CDS_SEC 1
J 0
(-325 250);
PAINT MONO (-325 250);
DISPLAY INVISIBLE (-325 250);
FORCEADD CAP_A..1
(-400 -650);
FORCEPROP 1 LAST TOLERANCE 20%
J 0
(-350 -700);
DISPLAY 0.617021 (-350 -700);
PAINT SKYBLUE (-350 -700);
FORCEPROP 1 LAST VOLTAGE 4V
J 0
(-350 -650);
DISPLAY 0.617021 (-350 -650);
PAINT SKYBLUE (-350 -650);
FORCEPROP 1 LAST MATERIAL X6S
J 0
(-350 -750);
DISPLAY 0.617021 (-350 -750);
PAINT SKYBLUE (-350 -750);
FORCEPROP 1 LAST PACK_TYPE 0603V
J 0
(-350 -850);
DISPLAY 0.617021 (-350 -850);
PAINT SKYBLUE (-350 -850);
FORCEPROP 1 LAST VALUE 22.0UF
J 0
(-350 -600);
DISPLAY 0.617021 (-350 -600);
PAINT SKYBLUE (-350 -600);
FORCEPROP 1 LAST PART_NUMBER E15431-004
J 0
(-350 -800);
DISPLAY 0.617021 (-350 -800);
PAINT BLUE (-350 -800);
FORCEPROP 1 LAST LOCATION C5G6
J 0
(-350 -550);
DISPLAY 0.617021 (-350 -550);
PAINT AQUA (-350 -550);
FORCEPROP 1 LASTPIN (-400 -750) $PN 2
J 0
(-390 -770);
DISPLAY 0.787234 (-390 -770);
PAINT ORANGE (-390 -770);
DISPLAY INVISIBLE (-390 -770);
FORCEPROP 1 LASTPIN (-400 -550) $PN 1
J 0
(-390 -570);
DISPLAY 0.787234 (-390 -570);
PAINT ORANGE (-390 -570);
DISPLAY INVISIBLE (-390 -570);
FORCEPROP 2 LAST CDS_LIB dev_discrete
J 0
(-400 -650);
PAINT ORANGE (-400 -650);
DISPLAY INVISIBLE (-400 -650);
FORCEPROP 2 LAST CDS_LOCATION C5G6
J 0
(-350 -550);
DISPLAY 0.617021 (-350 -550);
PAINT AQUA (-350 -550);
DISPLAY INVISIBLE (-350 -550);
FORCEPROP 2 LAST CDS_SEC 1
J 0
(-350 -450);
PAINT MONO (-350 -450);
DISPLAY INVISIBLE (-350 -450);
FORCEPROP 2 LAST $SEC 1
J 0
(-350 -450);
PAINT MONO (-350 -450);
DISPLAY INVISIBLE (-350 -450);
FORCEPROP 1 LAST PATH I237
J 0
(-350 -500);
DISPLAY 0.978723 (-350 -500);
PAINT WHITE (-350 -500);
DISPLAY INVISIBLE (-350 -500);
FORCEPROP 0 LAST ROOM PVDDQ_ABC
J 0
(-350 -450);
DISPLAY 1.021277 (-350 -450);
PAINT ORANGE (-350 -450);
DISPLAY INVISIBLE (-350 -450);
FORCEADD CAP_A..1
(-675 50);
FORCEPROP 1 LAST MATERIAL X6S
J 0
(-625 -50);
DISPLAY 0.617021 (-625 -50);
PAINT SKYBLUE (-625 -50);
FORCEPROP 1 LAST PACK_TYPE 0603V
J 0
(-625 -150);
DISPLAY 0.617021 (-625 -150);
PAINT SKYBLUE (-625 -150);
FORCEPROP 1 LAST PART_NUMBER E15431-004
J 0
(-625 -100);
DISPLAY 0.617021 (-625 -100);
PAINT BLUE (-625 -100);
FORCEPROP 1 LAST TOLERANCE 20%
J 0
(-625 0);
DISPLAY 0.617021 (-625 0);
PAINT SKYBLUE (-625 0);
FORCEPROP 1 LAST VOLTAGE 4V
J 0
(-625 50);
DISPLAY 0.617021 (-625 50);
PAINT SKYBLUE (-625 50);
FORCEPROP 1 LAST VALUE 22.0UF
J 0
(-625 100);
DISPLAY 0.617021 (-625 100);
PAINT SKYBLUE (-625 100);
FORCEPROP 1 LAST LOCATION C5U6
J 0
(-625 150);
DISPLAY 0.617021 (-625 150);
PAINT AQUA (-625 150);
FORCEPROP 1 LASTPIN (-675 -50) $PN 2
J 0
(-665 -70);
DISPLAY 0.787234 (-665 -70);
PAINT ORANGE (-665 -70);
DISPLAY INVISIBLE (-665 -70);
FORCEPROP 2 LAST CDS_LIB dev_discrete
J 0
(-675 50);
PAINT ORANGE (-675 50);
DISPLAY INVISIBLE (-675 50);
FORCEPROP 1 LASTPIN (-675 150) $PN 1
J 0
(-665 130);
DISPLAY 0.787234 (-665 130);
PAINT ORANGE (-665 130);
DISPLAY INVISIBLE (-665 130);
FORCEPROP 2 LAST CDS_LOCATION C5U6
J 0
(-625 150);
DISPLAY 0.617021 (-625 150);
PAINT AQUA (-625 150);
DISPLAY INVISIBLE (-625 150);
FORCEPROP 1 LAST PATH I238
J 0
(-625 200);
DISPLAY 0.978723 (-625 200);
PAINT WHITE (-625 200);
DISPLAY INVISIBLE (-625 200);
FORCEPROP 0 LAST ROOM PVDDQ_ABC
J 0
(-625 250);
DISPLAY 1.021277 (-625 250);
PAINT ORANGE (-625 250);
DISPLAY INVISIBLE (-625 250);
FORCEPROP 2 LAST $SEC 1
J 0
(-625 250);
PAINT MONO (-625 250);
DISPLAY INVISIBLE (-625 250);
FORCEPROP 2 LAST CDS_SEC 1
J 0
(-625 250);
PAINT MONO (-625 250);
DISPLAY INVISIBLE (-625 250);
FORCEADD CAP_A..1
(-950 50);
FORCEPROP 1 LAST MATERIAL X6S
J 0
(-900 -50);
DISPLAY 0.617021 (-900 -50);
PAINT SKYBLUE (-900 -50);
FORCEPROP 1 LAST PACK_TYPE 0603V
J 0
(-900 -150);
DISPLAY 0.617021 (-900 -150);
PAINT SKYBLUE (-900 -150);
FORCEPROP 1 LAST PART_NUMBER E15431-004
J 0
(-900 -100);
DISPLAY 0.617021 (-900 -100);
PAINT BLUE (-900 -100);
FORCEPROP 1 LAST TOLERANCE 20%
J 0
(-900 0);
DISPLAY 0.617021 (-900 0);
PAINT SKYBLUE (-900 0);
FORCEPROP 1 LAST VOLTAGE 4V
J 0
(-900 50);
DISPLAY 0.617021 (-900 50);
PAINT SKYBLUE (-900 50);
FORCEPROP 1 LAST LOCATION C5U5
J 0
(-900 150);
DISPLAY 0.617021 (-900 150);
PAINT AQUA (-900 150);
FORCEPROP 1 LAST VALUE 22.0UF
J 0
(-900 100);
DISPLAY 0.617021 (-900 100);
PAINT SKYBLUE (-900 100);
FORCEPROP 1 LASTPIN (-950 -50) $PN 2
J 0
(-940 -70);
DISPLAY 0.787234 (-940 -70);
PAINT ORANGE (-940 -70);
DISPLAY INVISIBLE (-940 -70);
FORCEPROP 2 LAST CDS_LIB dev_discrete
J 0
(-950 50);
PAINT ORANGE (-950 50);
DISPLAY INVISIBLE (-950 50);
FORCEPROP 1 LASTPIN (-950 150) $PN 1
J 0
(-940 130);
DISPLAY 0.787234 (-940 130);
PAINT ORANGE (-940 130);
DISPLAY INVISIBLE (-940 130);
FORCEPROP 1 LAST PATH I239
J 0
(-900 200);
DISPLAY 0.978723 (-900 200);
PAINT WHITE (-900 200);
DISPLAY INVISIBLE (-900 200);
FORCEPROP 2 LAST CDS_LOCATION C5U5
J 0
(-900 150);
DISPLAY 0.617021 (-900 150);
PAINT AQUA (-900 150);
DISPLAY INVISIBLE (-900 150);
FORCEPROP 0 LAST ROOM PVDDQ_ABC
J 0
(-900 250);
DISPLAY 1.021277 (-900 250);
PAINT ORANGE (-900 250);
DISPLAY INVISIBLE (-900 250);
FORCEPROP 2 LAST $SEC 1
J 0
(-900 250);
PAINT MONO (-900 250);
DISPLAY INVISIBLE (-900 250);
FORCEPROP 2 LAST CDS_SEC 1
J 0
(-900 250);
PAINT MONO (-900 250);
DISPLAY INVISIBLE (-900 250);
FORCEADD CAP_A..1
(-700 -650);
FORCEPROP 1 LASTPIN (-700 -750) $PN 2
J 0
(-690 -770);
DISPLAY 0.617021 (-690 -770);
PAINT ORANGE (-690 -770);
FORCEPROP 1 LAST TOLERANCE 20%
J 0
(-650 -700);
DISPLAY 0.617021 (-650 -700);
PAINT SKYBLUE (-650 -700);
FORCEPROP 1 LAST VOLTAGE 4V
J 0
(-650 -650);
DISPLAY 0.617021 (-650 -650);
PAINT SKYBLUE (-650 -650);
FORCEPROP 1 LAST MATERIAL X6S
J 0
(-650 -750);
DISPLAY 0.617021 (-650 -750);
PAINT SKYBLUE (-650 -750);
FORCEPROP 1 LASTPIN (-700 -550) $PN 1
J 0
(-690 -570);
DISPLAY 0.617021 (-690 -570);
PAINT ORANGE (-690 -570);
FORCEPROP 1 LAST PACK_TYPE 0603V
J 0
(-650 -850);
DISPLAY 0.617021 (-650 -850);
PAINT SKYBLUE (-650 -850);
FORCEPROP 1 LAST VALUE 22.0UF
J 0
(-650 -600);
DISPLAY 0.617021 (-650 -600);
PAINT SKYBLUE (-650 -600);
FORCEPROP 1 LAST PART_NUMBER E15431-004
J 0
(-650 -800);
DISPLAY 0.617021 (-650 -800);
PAINT BLUE (-650 -800);
FORCEPROP 1 LAST LOCATION C5G13
J 0
(-650 -550);
DISPLAY 0.617021 (-650 -550);
PAINT AQUA (-650 -550);
FORCEPROP 2 LAST CDS_LIB dev_discrete
J 0
(-700 -650);
PAINT ORANGE (-700 -650);
DISPLAY INVISIBLE (-700 -650);
FORCEPROP 2 LAST CDS_LOCATION C5G13
J 0
(-650 -550);
DISPLAY 0.617021 (-650 -550);
PAINT AQUA (-650 -550);
DISPLAY INVISIBLE (-650 -550);
FORCEPROP 2 LAST CDS_SEC 1
J 0
(-650 -500);
PAINT ORANGE (-650 -500);
DISPLAY INVISIBLE (-650 -500);
FORCEPROP 2 LAST SEC_TYPE 0603V
J 0
(-650 -450);
DISPLAY 1.021277 (-650 -450);
PAINT ORANGE (-650 -450);
DISPLAY INVISIBLE (-650 -450);
FORCEPROP 2 LAST SEC 1
J 0
(-650 -450);
DISPLAY 0.680851 (-650 -450);
PAINT MONO (-650 -450);
DISPLAY INVISIBLE (-650 -450);
FORCEPROP 1 LAST PATH I240
J 0
(-650 -500);
DISPLAY 0.978723 (-650 -500);
PAINT WHITE (-650 -500);
DISPLAY INVISIBLE (-650 -500);
FORCEPROP 0 LAST ROOM PVDDQ_ABC
J 0
(-650 -450);
DISPLAY 1.021277 (-650 -450);
PAINT ORANGE (-650 -450);
DISPLAY INVISIBLE (-650 -450);
FORCEADD CAP_A..1
(-975 -650);
FORCEPROP 1 LAST PACK_TYPE 0603V
J 0
(-925 -850);
DISPLAY 0.617021 (-925 -850);
PAINT SKYBLUE (-925 -850);
FORCEPROP 1 LAST LOCATION C5G4
J 0
(-925 -550);
DISPLAY 0.617021 (-925 -550);
PAINT AQUA (-925 -550);
FORCEPROP 1 LAST TOLERANCE 20%
J 0
(-925 -700);
DISPLAY 0.617021 (-925 -700);
PAINT SKYBLUE (-925 -700);
FORCEPROP 1 LAST VOLTAGE 4V
J 0
(-925 -650);
DISPLAY 0.617021 (-925 -650);
PAINT SKYBLUE (-925 -650);
FORCEPROP 1 LAST MATERIAL X6S
J 0
(-925 -750);
DISPLAY 0.617021 (-925 -750);
PAINT SKYBLUE (-925 -750);
FORCEPROP 1 LAST VALUE 22.0UF
J 0
(-925 -600);
DISPLAY 0.617021 (-925 -600);
PAINT SKYBLUE (-925 -600);
FORCEPROP 1 LAST PART_NUMBER E15431-004
J 0
(-925 -800);
DISPLAY 0.617021 (-925 -800);
PAINT BLUE (-925 -800);
FORCEPROP 1 LASTPIN (-975 -750) $PN 2
J 0
(-965 -770);
DISPLAY 0.787234 (-965 -770);
PAINT ORANGE (-965 -770);
DISPLAY INVISIBLE (-965 -770);
FORCEPROP 1 LASTPIN (-975 -550) $PN 1
J 0
(-965 -570);
DISPLAY 0.787234 (-965 -570);
PAINT ORANGE (-965 -570);
DISPLAY INVISIBLE (-965 -570);
FORCEPROP 2 LAST CDS_LIB dev_discrete
J 0
(-975 -650);
PAINT ORANGE (-975 -650);
DISPLAY INVISIBLE (-975 -650);
FORCEPROP 2 LAST CDS_LOCATION C5G4
J 0
(-925 -550);
DISPLAY 0.617021 (-925 -550);
PAINT AQUA (-925 -550);
DISPLAY INVISIBLE (-925 -550);
FORCEPROP 2 LAST CDS_SEC 1
J 0
(-925 -450);
PAINT MONO (-925 -450);
DISPLAY INVISIBLE (-925 -450);
FORCEPROP 2 LAST $SEC 1
J 0
(-925 -450);
PAINT MONO (-925 -450);
DISPLAY INVISIBLE (-925 -450);
FORCEPROP 1 LAST PATH I241
J 0
(-925 -500);
DISPLAY 0.978723 (-925 -500);
PAINT WHITE (-925 -500);
DISPLAY INVISIBLE (-925 -500);
FORCEPROP 0 LAST ROOM PVDDQ_ABC
J 0
(-925 -450);
DISPLAY 1.021277 (-925 -450);
PAINT ORANGE (-925 -450);
DISPLAY INVISIBLE (-925 -450);
FORCEADD PVDDQ_ABC..1
(-1825 300);
FORCEPROP 3 LASTPIN (-1825 250) SIG_NAME PVDDQ_ABC\g
J 0
(-1815 260);
DISPLAY 0.659574 (-1815 260);
PAINT MONO (-1815 260);
DISPLAY INVISIBLE (-1815 260);
FORCEPROP 1 LAST HDL_POWER PVDDQ_ABC
J 1
(-1825 350);
DISPLAY 0.872340 (-1825 350);
PAINT GREEN (-1825 350);
DISPLAY INVISIBLE (-1825 350);
FORCEPROP 2 LAST ROOM VDDQ_ABC_PWR_VR
J 0
(-1825 400);
DISPLAY 1.936170 (-1825 400);
PAINT ORANGE (-1825 400);
DISPLAY INVISIBLE (-1825 400);
FORCEPROP 1 LAST BODY_TYPE PLUMBING
J 0
(-1870 257);
DISPLAY 0.340426 (-1870 257);
PAINT GREEN (-1870 257);
DISPLAY INVISIBLE (-1870 257);
FORCEPROP 2 LAST CDS_LIB mstr_symbols
J 0
(-1825 300);
PAINT ORANGE (-1825 300);
DISPLAY INVISIBLE (-1825 300);
FORCEPROP 2 LAST BOM_COST PROC_SOCKET 
J 0
(-1825 400);
DISPLAY 1.446809 (-1825 400);
PAINT MONO (-1825 400);
DISPLAY INVISIBLE (-1825 400);
FORCEPROP 1 LAST VOLTAGE 1.2V
J 0
(-1870 257);
DISPLAY 0.340426 (-1870 257);
PAINT SKYBLUE (-1870 257);
DISPLAY INVISIBLE (-1870 257);
FORCEPROP 1 LAST PATH I242
J 0
(-1775 325);
DISPLAY 0.872340 (-1775 325);
PAINT AQUA (-1775 325);
DISPLAY INVISIBLE (-1775 325);
FORCEADD CAP_A..1
(-1225 50);
FORCEPROP 1 LAST PACK_TYPE 0603V
J 0
(-1175 -150);
DISPLAY 0.617021 (-1175 -150);
PAINT SKYBLUE (-1175 -150);
FORCEPROP 1 LAST MATERIAL X6S
J 0
(-1175 -50);
DISPLAY 0.617021 (-1175 -50);
PAINT SKYBLUE (-1175 -50);
FORCEPROP 1 LAST PART_NUMBER E15431-004
J 0
(-1175 -100);
DISPLAY 0.617021 (-1175 -100);
PAINT BLUE (-1175 -100);
FORCEPROP 1 LAST TOLERANCE 20%
J 0
(-1175 0);
DISPLAY 0.617021 (-1175 0);
PAINT SKYBLUE (-1175 0);
FORCEPROP 1 LAST VOLTAGE 4V
J 0
(-1175 50);
DISPLAY 0.617021 (-1175 50);
PAINT SKYBLUE (-1175 50);
FORCEPROP 1 LAST LOCATION C5U4
J 0
(-1175 150);
DISPLAY 0.617021 (-1175 150);
PAINT AQUA (-1175 150);
FORCEPROP 1 LAST VALUE 22.0UF
J 0
(-1175 100);
DISPLAY 0.617021 (-1175 100);
PAINT SKYBLUE (-1175 100);
FORCEPROP 1 LASTPIN (-1225 -50) $PN 2
J 0
(-1215 -70);
DISPLAY 0.787234 (-1215 -70);
PAINT ORANGE (-1215 -70);
DISPLAY INVISIBLE (-1215 -70);
FORCEPROP 2 LAST CDS_LIB dev_discrete
J 0
(-1225 50);
PAINT ORANGE (-1225 50);
DISPLAY INVISIBLE (-1225 50);
FORCEPROP 1 LASTPIN (-1225 150) $PN 1
J 0
(-1215 130);
DISPLAY 0.787234 (-1215 130);
PAINT ORANGE (-1215 130);
DISPLAY INVISIBLE (-1215 130);
FORCEPROP 1 LAST PATH I243
J 0
(-1175 200);
DISPLAY 0.978723 (-1175 200);
PAINT WHITE (-1175 200);
DISPLAY INVISIBLE (-1175 200);
FORCEPROP 2 LAST CDS_LOCATION C5U4
J 0
(-1175 150);
DISPLAY 0.617021 (-1175 150);
PAINT AQUA (-1175 150);
DISPLAY INVISIBLE (-1175 150);
FORCEPROP 0 LAST ROOM PVDDQ_ABC
J 0
(-1175 250);
DISPLAY 1.021277 (-1175 250);
PAINT ORANGE (-1175 250);
DISPLAY INVISIBLE (-1175 250);
FORCEPROP 2 LAST $SEC 1
J 0
(-1175 250);
PAINT MONO (-1175 250);
DISPLAY INVISIBLE (-1175 250);
FORCEPROP 2 LAST CDS_SEC 1
J 0
(-1175 250);
PAINT MONO (-1175 250);
DISPLAY INVISIBLE (-1175 250);
FORCEADD CAP_A..1
(-1525 50);
FORCEPROP 1 LAST PACK_TYPE 0603V
J 0
(-1475 -150);
DISPLAY 0.617021 (-1475 -150);
PAINT SKYBLUE (-1475 -150);
FORCEPROP 1 LAST MATERIAL X6S
J 0
(-1475 -50);
DISPLAY 0.617021 (-1475 -50);
PAINT SKYBLUE (-1475 -50);
FORCEPROP 1 LAST PART_NUMBER E15431-004
J 0
(-1475 -100);
DISPLAY 0.617021 (-1475 -100);
PAINT BLUE (-1475 -100);
FORCEPROP 1 LAST TOLERANCE 20%
J 0
(-1475 0);
DISPLAY 0.617021 (-1475 0);
PAINT SKYBLUE (-1475 0);
FORCEPROP 1 LAST VOLTAGE 4V
J 0
(-1475 50);
DISPLAY 0.617021 (-1475 50);
PAINT SKYBLUE (-1475 50);
FORCEPROP 1 LAST VALUE 22.0UF
J 0
(-1475 100);
DISPLAY 0.617021 (-1475 100);
PAINT SKYBLUE (-1475 100);
FORCEPROP 1 LAST LOCATION C5U3
J 0
(-1475 150);
DISPLAY 0.617021 (-1475 150);
PAINT AQUA (-1475 150);
FORCEPROP 1 LASTPIN (-1525 -50) $PN 2
J 0
(-1515 -70);
DISPLAY 0.787234 (-1515 -70);
PAINT ORANGE (-1515 -70);
DISPLAY INVISIBLE (-1515 -70);
FORCEPROP 2 LAST CDS_LOCATION C5U3
J 0
(-1475 150);
DISPLAY 0.617021 (-1475 150);
PAINT AQUA (-1475 150);
DISPLAY INVISIBLE (-1475 150);
FORCEPROP 2 LAST CDS_LIB dev_discrete
J 0
(-1525 50);
PAINT ORANGE (-1525 50);
DISPLAY INVISIBLE (-1525 50);
FORCEPROP 1 LAST PATH I244
J 0
(-1475 200);
DISPLAY 0.978723 (-1475 200);
PAINT WHITE (-1475 200);
DISPLAY INVISIBLE (-1475 200);
FORCEPROP 1 LASTPIN (-1525 150) $PN 1
J 0
(-1515 130);
DISPLAY 0.787234 (-1515 130);
PAINT ORANGE (-1515 130);
DISPLAY INVISIBLE (-1515 130);
FORCEPROP 0 LAST ROOM PVDDQ_ABC
J 0
(-1475 250);
DISPLAY 1.021277 (-1475 250);
PAINT ORANGE (-1475 250);
DISPLAY INVISIBLE (-1475 250);
FORCEPROP 2 LAST $SEC 1
J 0
(-1475 250);
PAINT MONO (-1475 250);
DISPLAY INVISIBLE (-1475 250);
FORCEPROP 2 LAST CDS_SEC 1
J 0
(-1475 250);
PAINT MONO (-1475 250);
DISPLAY INVISIBLE (-1475 250);
FORCEADD CAP_A..1
(-1250 -650);
FORCEPROP 1 LAST PACK_TYPE 0603V
J 0
(-1200 -850);
DISPLAY 0.617021 (-1200 -850);
PAINT SKYBLUE (-1200 -850);
FORCEPROP 1 LAST LOCATION C5G2
J 0
(-1200 -550);
DISPLAY 0.617021 (-1200 -550);
PAINT AQUA (-1200 -550);
FORCEPROP 1 LAST VALUE 22.0UF
J 0
(-1200 -600);
DISPLAY 0.617021 (-1200 -600);
PAINT SKYBLUE (-1200 -600);
FORCEPROP 1 LAST TOLERANCE 20%
J 0
(-1200 -700);
DISPLAY 0.617021 (-1200 -700);
PAINT SKYBLUE (-1200 -700);
FORCEPROP 1 LAST VOLTAGE 4V
J 0
(-1200 -650);
DISPLAY 0.617021 (-1200 -650);
PAINT SKYBLUE (-1200 -650);
FORCEPROP 1 LAST MATERIAL X6S
J 0
(-1200 -750);
DISPLAY 0.617021 (-1200 -750);
PAINT SKYBLUE (-1200 -750);
FORCEPROP 1 LAST PART_NUMBER E15431-004
J 0
(-1200 -800);
DISPLAY 0.617021 (-1200 -800);
PAINT BLUE (-1200 -800);
FORCEPROP 1 LASTPIN (-1250 -750) $PN 2
J 0
(-1240 -770);
DISPLAY 0.787234 (-1240 -770);
PAINT ORANGE (-1240 -770);
DISPLAY INVISIBLE (-1240 -770);
FORCEPROP 1 LASTPIN (-1250 -550) $PN 1
J 0
(-1240 -570);
DISPLAY 0.787234 (-1240 -570);
PAINT ORANGE (-1240 -570);
DISPLAY INVISIBLE (-1240 -570);
FORCEPROP 2 LAST CDS_LIB dev_discrete
J 0
(-1250 -650);
PAINT ORANGE (-1250 -650);
DISPLAY INVISIBLE (-1250 -650);
FORCEPROP 2 LAST CDS_LOCATION C5G2
J 0
(-1200 -550);
DISPLAY 0.617021 (-1200 -550);
PAINT AQUA (-1200 -550);
DISPLAY INVISIBLE (-1200 -550);
FORCEPROP 2 LAST CDS_SEC 1
J 0
(-1200 -450);
PAINT MONO (-1200 -450);
DISPLAY INVISIBLE (-1200 -450);
FORCEPROP 2 LAST $SEC 1
J 0
(-1200 -450);
PAINT MONO (-1200 -450);
DISPLAY INVISIBLE (-1200 -450);
FORCEPROP 1 LAST PATH I245
J 0
(-1200 -500);
DISPLAY 0.978723 (-1200 -500);
PAINT WHITE (-1200 -500);
DISPLAY INVISIBLE (-1200 -500);
FORCEPROP 0 LAST ROOM PVDDQ_ABC
J 0
(-1200 -450);
DISPLAY 1.021277 (-1200 -450);
PAINT ORANGE (-1200 -450);
DISPLAY INVISIBLE (-1200 -450);
FORCEADD CAP_A..1
(-1550 -650);
FORCEPROP 1 LAST LOCATION C5G12
J 0
(-1500 -550);
DISPLAY 0.617021 (-1500 -550);
PAINT AQUA (-1500 -550);
FORCEPROP 1 LAST VALUE 22.0UF
J 0
(-1500 -600);
DISPLAY 0.617021 (-1500 -600);
PAINT SKYBLUE (-1500 -600);
FORCEPROP 1 LAST TOLERANCE 20%
J 0
(-1500 -700);
DISPLAY 0.617021 (-1500 -700);
PAINT SKYBLUE (-1500 -700);
FORCEPROP 1 LAST MATERIAL X6S
J 0
(-1500 -750);
DISPLAY 0.617021 (-1500 -750);
PAINT SKYBLUE (-1500 -750);
FORCEPROP 1 LAST VOLTAGE 4V
J 0
(-1500 -650);
DISPLAY 0.617021 (-1500 -650);
PAINT SKYBLUE (-1500 -650);
FORCEPROP 1 LAST PACK_TYPE 0603V
J 0
(-1500 -850);
DISPLAY 0.617021 (-1500 -850);
PAINT SKYBLUE (-1500 -850);
FORCEPROP 1 LAST PART_NUMBER E15431-004
J 0
(-1500 -800);
DISPLAY 0.617021 (-1500 -800);
PAINT BLUE (-1500 -800);
FORCEPROP 1 LASTPIN (-1550 -750) $PN 2
J 0
(-1540 -770);
DISPLAY 0.787234 (-1540 -770);
PAINT ORANGE (-1540 -770);
DISPLAY INVISIBLE (-1540 -770);
FORCEPROP 1 LASTPIN (-1550 -550) $PN 1
J 0
(-1540 -570);
DISPLAY 0.787234 (-1540 -570);
PAINT ORANGE (-1540 -570);
DISPLAY INVISIBLE (-1540 -570);
FORCEPROP 2 LAST CDS_LIB dev_discrete
J 0
(-1550 -650);
PAINT ORANGE (-1550 -650);
DISPLAY INVISIBLE (-1550 -650);
FORCEPROP 2 LAST CDS_LOCATION C5G12
J 0
(-1500 -550);
DISPLAY 0.617021 (-1500 -550);
PAINT AQUA (-1500 -550);
DISPLAY INVISIBLE (-1500 -550);
FORCEPROP 0 LAST ROOM PVDDQ_ABC
J 0
(-1500 -450);
DISPLAY 1.021277 (-1500 -450);
PAINT ORANGE (-1500 -450);
DISPLAY INVISIBLE (-1500 -450);
FORCEPROP 2 LAST $SEC 1
J 0
(-1500 -450);
PAINT MONO (-1500 -450);
DISPLAY INVISIBLE (-1500 -450);
FORCEPROP 2 LAST CDS_SEC 1
J 0
(-1500 -450);
PAINT MONO (-1500 -450);
DISPLAY INVISIBLE (-1500 -450);
FORCEPROP 1 LAST PATH I246
J 0
(-1500 -500);
DISPLAY 0.978723 (-1500 -500);
PAINT WHITE (-1500 -500);
DISPLAY INVISIBLE (-1500 -500);
FORCEADD CAP_A..1
(-1825 50);
FORCEPROP 1 LAST MATERIAL X6S
J 0
(-1775 -50);
DISPLAY 0.617021 (-1775 -50);
PAINT SKYBLUE (-1775 -50);
FORCEPROP 1 LAST PACK_TYPE 0603V
J 0
(-1775 -150);
DISPLAY 0.617021 (-1775 -150);
PAINT SKYBLUE (-1775 -150);
FORCEPROP 1 LAST PART_NUMBER E15431-004
J 0
(-1775 -100);
DISPLAY 0.617021 (-1775 -100);
PAINT BLUE (-1775 -100);
FORCEPROP 1 LAST TOLERANCE 20%
J 0
(-1775 0);
DISPLAY 0.617021 (-1775 0);
PAINT SKYBLUE (-1775 0);
FORCEPROP 1 LAST VOLTAGE 4V
J 0
(-1775 50);
DISPLAY 0.617021 (-1775 50);
PAINT SKYBLUE (-1775 50);
FORCEPROP 1 LAST VALUE 22.0UF
J 0
(-1775 100);
DISPLAY 0.617021 (-1775 100);
PAINT SKYBLUE (-1775 100);
FORCEPROP 1 LAST LOCATION C5U2
J 0
(-1775 150);
DISPLAY 0.617021 (-1775 150);
PAINT AQUA (-1775 150);
FORCEPROP 1 LASTPIN (-1825 -50) $PN 2
J 0
(-1815 -70);
DISPLAY 0.787234 (-1815 -70);
PAINT ORANGE (-1815 -70);
DISPLAY INVISIBLE (-1815 -70);
FORCEPROP 2 LAST CDS_LIB dev_discrete
J 0
(-1825 50);
PAINT ORANGE (-1825 50);
DISPLAY INVISIBLE (-1825 50);
FORCEPROP 1 LASTPIN (-1825 150) $PN 1
J 0
(-1815 130);
DISPLAY 0.787234 (-1815 130);
PAINT ORANGE (-1815 130);
DISPLAY INVISIBLE (-1815 130);
FORCEPROP 2 LAST CDS_LOCATION C5U2
J 0
(-1775 150);
DISPLAY 0.617021 (-1775 150);
PAINT AQUA (-1775 150);
DISPLAY INVISIBLE (-1775 150);
FORCEPROP 2 LAST CDS_SEC 1
J 0
(-1775 250);
PAINT MONO (-1775 250);
DISPLAY INVISIBLE (-1775 250);
FORCEPROP 2 LAST $SEC 1
J 0
(-1775 250);
PAINT MONO (-1775 250);
DISPLAY INVISIBLE (-1775 250);
FORCEPROP 1 LAST PATH I247
J 0
(-1775 200);
DISPLAY 0.978723 (-1775 200);
PAINT WHITE (-1775 200);
DISPLAY INVISIBLE (-1775 200);
FORCEPROP 0 LAST ROOM PVDDQ_ABC
J 0
(-1775 250);
DISPLAY 1.021277 (-1775 250);
PAINT ORANGE (-1775 250);
DISPLAY INVISIBLE (-1775 250);
FORCEADD GND..1
(-1825 -225);
FORCEPROP 3 LASTPIN (-1825 -175) SIG_NAME GND\g
J 0
(-1815 -165);
DISPLAY 0.659574 (-1815 -165);
PAINT MONO (-1815 -165);
DISPLAY INVISIBLE (-1815 -165);
FORCEPROP 2 LAST BOM_COST PROC_VRD_VCCIN_CPU0
J 0
(-2200 -150);
DISPLAY 1.446809 (-2200 -150);
PAINT MONO (-2200 -150);
DISPLAY INVISIBLE (-2200 -150);
FORCEPROP 2 LAST ROOM VDDQ_ABC_PWR_VR
J 0
(-2375 -150);
DISPLAY 1.936170 (-2375 -150);
PAINT ORANGE (-2375 -150);
DISPLAY INVISIBLE (-2375 -150);
FORCEPROP 1 LAST BODY_TYPE PLUMBING
J 0
(-1870 -268);
DISPLAY 0.340426 (-1870 -268);
PAINT GREEN (-1870 -268);
DISPLAY INVISIBLE (-1870 -268);
FORCEPROP 2 LAST CDS_LIB mstr_symbols
J 0
(-1825 -225);
PAINT ORANGE (-1825 -225);
DISPLAY INVISIBLE (-1825 -225);
FORCEPROP 1 LAST VOLTAGE 0
J 0
(-1825 -225);
PAINT SKYBLUE (-1825 -225);
DISPLAY INVISIBLE (-1825 -225);
FORCEPROP 1 LAST HDL_POWER GND
J 0
(-1825 -75);
DISPLAY 1.723404 (-1825 -75);
PAINT GREEN (-1825 -75);
DISPLAY INVISIBLE (-1825 -75);
FORCEPROP 1 LAST SIZE 1B
J 0
(-1750 -275);
DISPLAY 1.723404 (-1750 -275);
PAINT GREEN (-1750 -275);
DISPLAY INVISIBLE (-1750 -275);
FORCEPROP 1 LAST PATH I248
J 0
(-1750 -225);
DISPLAY 0.872340 (-1750 -225);
PAINT AQUA (-1750 -225);
DISPLAY INVISIBLE (-1750 -225);
FORCEADD PVDDQ_ABC..1
(-1850 -400);
FORCEPROP 3 LASTPIN (-1850 -450) SIG_NAME PVDDQ_ABC\g
J 0
(-1840 -440);
DISPLAY 0.659574 (-1840 -440);
PAINT MONO (-1840 -440);
DISPLAY INVISIBLE (-1840 -440);
FORCEPROP 1 LAST VOLTAGE 1.2V
J 0
(-1895 -443);
DISPLAY 0.340426 (-1895 -443);
PAINT SKYBLUE (-1895 -443);
DISPLAY INVISIBLE (-1895 -443);
FORCEPROP 1 LAST BODY_TYPE PLUMBING
J 0
(-1895 -443);
DISPLAY 0.340426 (-1895 -443);
PAINT GREEN (-1895 -443);
DISPLAY INVISIBLE (-1895 -443);
FORCEPROP 2 LAST CDS_LIB mstr_symbols
J 0
(-1850 -400);
PAINT ORANGE (-1850 -400);
DISPLAY INVISIBLE (-1850 -400);
FORCEPROP 1 LAST PATH I249
J 0
(-1800 -375);
DISPLAY 0.872340 (-1800 -375);
PAINT AQUA (-1800 -375);
DISPLAY INVISIBLE (-1800 -375);
FORCEPROP 1 LAST HDL_POWER PVDDQ_ABC
J 1
(-1850 -350);
DISPLAY 0.872340 (-1850 -350);
PAINT GREEN (-1850 -350);
DISPLAY INVISIBLE (-1850 -350);
FORCEPROP 2 LAST BOM_COST PROC_SOCKET 
J 0
(-1850 -300);
DISPLAY 1.446809 (-1850 -300);
PAINT MONO (-1850 -300);
DISPLAY INVISIBLE (-1850 -300);
FORCEPROP 2 LAST ROOM VDDQ_ABC_PWR_VR
J 0
(-1850 -300);
DISPLAY 1.936170 (-1850 -300);
PAINT ORANGE (-1850 -300);
DISPLAY INVISIBLE (-1850 -300);
FORCEADD CAP_A..1
(-1850 -650);
FORCEPROP 1 LASTPIN (-1850 -750) $PN 2
J 0
(-1840 -770);
DISPLAY 0.617021 (-1840 -770);
PAINT ORANGE (-1840 -770);
FORCEPROP 1 LASTPIN (-1850 -550) $PN 1
J 0
(-1840 -570);
DISPLAY 0.617021 (-1840 -570);
PAINT ORANGE (-1840 -570);
FORCEPROP 1 LAST MATERIAL X6S
J 0
(-1800 -750);
DISPLAY 0.617021 (-1800 -750);
PAINT SKYBLUE (-1800 -750);
FORCEPROP 1 LAST VOLTAGE 4V
J 0
(-1800 -650);
DISPLAY 0.617021 (-1800 -650);
PAINT SKYBLUE (-1800 -650);
FORCEPROP 1 LAST PACK_TYPE 0603V
J 0
(-1800 -850);
DISPLAY 0.617021 (-1800 -850);
PAINT SKYBLUE (-1800 -850);
FORCEPROP 1 LAST TOLERANCE 20%
J 0
(-1800 -700);
DISPLAY 0.617021 (-1800 -700);
PAINT SKYBLUE (-1800 -700);
FORCEPROP 1 LAST VALUE 22.0UF
J 0
(-1800 -600);
DISPLAY 0.617021 (-1800 -600);
PAINT SKYBLUE (-1800 -600);
FORCEPROP 1 LAST LOCATION C5G11
J 0
(-1800 -550);
DISPLAY 0.617021 (-1800 -550);
PAINT AQUA (-1800 -550);
FORCEPROP 1 LAST PART_NUMBER E15431-004
J 0
(-1800 -800);
DISPLAY 0.617021 (-1800 -800);
PAINT BLUE (-1800 -800);
FORCEPROP 2 LAST CDS_LOCATION C5G11
J 0
(-1800 -550);
DISPLAY 0.617021 (-1800 -550);
PAINT AQUA (-1800 -550);
DISPLAY INVISIBLE (-1800 -550);
FORCEPROP 2 LAST CDS_LIB dev_discrete
J 0
(-1850 -650);
PAINT ORANGE (-1850 -650);
DISPLAY INVISIBLE (-1850 -650);
FORCEPROP 0 LAST ROOM PVDDQ_ABC
J 0
(-1800 -450);
DISPLAY 1.021277 (-1800 -450);
PAINT ORANGE (-1800 -450);
DISPLAY INVISIBLE (-1800 -450);
FORCEPROP 2 LAST CDS_SEC 1
J 0
(-1800 -500);
PAINT ORANGE (-1800 -500);
DISPLAY INVISIBLE (-1800 -500);
FORCEPROP 2 LAST SEC 1
J 0
(-1800 -450);
DISPLAY 0.680851 (-1800 -450);
PAINT MONO (-1800 -450);
DISPLAY INVISIBLE (-1800 -450);
FORCEPROP 2 LAST SEC_TYPE 0603V
J 0
(-1800 -450);
DISPLAY 1.021277 (-1800 -450);
PAINT ORANGE (-1800 -450);
DISPLAY INVISIBLE (-1800 -450);
FORCEPROP 1 LAST PATH I250
J 0
(-1800 -500);
DISPLAY 0.978723 (-1800 -500);
PAINT WHITE (-1800 -500);
DISPLAY INVISIBLE (-1800 -500);
FORCEADD GND..1
(-1850 -925);
FORCEPROP 3 LASTPIN (-1850 -875) SIG_NAME GND\g
J 0
(-1840 -865);
DISPLAY 0.659574 (-1840 -865);
PAINT MONO (-1840 -865);
DISPLAY INVISIBLE (-1840 -865);
FORCEPROP 2 LAST BOM_COST PROC_VRD_VCCIN_CPU0
J 0
(-2225 -850);
DISPLAY 1.446809 (-2225 -850);
PAINT MONO (-2225 -850);
DISPLAY INVISIBLE (-2225 -850);
FORCEPROP 2 LAST ROOM VDDQ_ABC_PWR_VR
J 0
(-2400 -850);
DISPLAY 1.936170 (-2400 -850);
PAINT ORANGE (-2400 -850);
DISPLAY INVISIBLE (-2400 -850);
FORCEPROP 1 LAST BODY_TYPE PLUMBING
J 0
(-1895 -968);
DISPLAY 0.340426 (-1895 -968);
PAINT GREEN (-1895 -968);
DISPLAY INVISIBLE (-1895 -968);
FORCEPROP 2 LAST CDS_LIB mstr_symbols
J 0
(-1850 -925);
PAINT ORANGE (-1850 -925);
DISPLAY INVISIBLE (-1850 -925);
FORCEPROP 1 LAST VOLTAGE 0
J 0
(-1850 -925);
PAINT SKYBLUE (-1850 -925);
DISPLAY INVISIBLE (-1850 -925);
FORCEPROP 1 LAST HDL_POWER GND
J 0
(-1850 -775);
DISPLAY 1.723404 (-1850 -775);
PAINT GREEN (-1850 -775);
DISPLAY INVISIBLE (-1850 -775);
FORCEPROP 1 LAST PATH I251
J 0
(-1775 -925);
DISPLAY 0.872340 (-1775 -925);
PAINT AQUA (-1775 -925);
DISPLAY INVISIBLE (-1775 -925);
FORCEPROP 1 LAST SIZE 1B
J 0
(-1775 -975);
DISPLAY 1.723404 (-1775 -975);
PAINT GREEN (-1775 -975);
DISPLAY INVISIBLE (-1775 -975);
FORCEADD SHUNT..1
(125 1500);
FORCEPROP 1 LASTPIN (-25 1500) $PN 1
J 2
(25 1510);
DISPLAY 0.617021 (25 1510);
PAINT ORANGE (25 1510);
FORCEPROP 1 LAST PART_NUMBER N_A
J 0
(50 1410);
DISPLAY 0.617021 (50 1410);
PAINT BLUE (50 1410);
FORCEPROP 1 LASTPIN (275 1500) $PN 2
J 0
(235 1510);
DISPLAY 0.617021 (235 1510);
PAINT ORANGE (235 1510);
FORCEPROP 1 LAST LOCATION SH4U1
J 0
(50 1550);
DISPLAY 0.617021 (50 1550);
PAINT AQUA (50 1550);
FORCEPROP 1 LAST PIN_SHORT A:B
J 0
(50 1250);
DISPLAY 1.021277 (50 1250);
PAINT ORANGE (50 1250);
DISPLAY INVISIBLE (50 1250);
FORCEPROP 1 LAST PACK_TYPE SH0201
J 0
(65 1315);
DISPLAY 0.978723 (65 1315);
PAINT SKYBLUE (65 1315);
DISPLAY INVISIBLE (65 1315);
FORCEPROP 1 LAST MATERIAL EMPTY
J 0
(50 1365);
DISPLAY 0.978723 (50 1365);
PAINT RED (50 1365);
DISPLAY INVISIBLE (50 1365);
FORCEPROP 2 LAST CDS_LIB mstr_misc
J 0
(125 1500);
PAINT ORANGE (125 1500);
DISPLAY INVISIBLE (125 1500);
FORCEPROP 1 LAST PATH I259
J 0
(75 1600);
DISPLAY 0.978723 (75 1600);
PAINT ORANGE (75 1600);
DISPLAY INVISIBLE (75 1600);
FORCEPROP 0 LAST SEC 1
J 0
(50 1600);
DISPLAY 0.680851 (50 1600);
PAINT MONO (50 1600);
DISPLAY INVISIBLE (50 1600);
FORCEPROP 2 LAST SEC_TYPE SH0201
J 0
(75 1650);
DISPLAY 1.021277 (75 1650);
PAINT ORANGE (75 1650);
DISPLAY INVISIBLE (75 1650);
FORCEADD SHUNT..1
(150 1950);
FORCEPROP 1 LASTPIN (0 1950) $PN 1
J 2
(50 1960);
DISPLAY 0.617021 (50 1960);
PAINT ORANGE (50 1960);
FORCEPROP 1 LAST PART_NUMBER N_A
J 0
(75 1860);
DISPLAY 0.617021 (75 1860);
PAINT BLUE (75 1860);
FORCEPROP 1 LAST LOCATION SH4U2
J 0
(75 2000);
DISPLAY 0.617021 (75 2000);
PAINT AQUA (75 2000);
FORCEPROP 1 LASTPIN (300 1950) $PN 2
J 0
(260 1960);
DISPLAY 0.617021 (260 1960);
PAINT ORANGE (260 1960);
FORCEPROP 1 LAST PIN_SHORT A:B
J 0
(75 1700);
DISPLAY 1.021277 (75 1700);
PAINT ORANGE (75 1700);
DISPLAY INVISIBLE (75 1700);
FORCEPROP 1 LAST PACK_TYPE SH0201
J 0
(90 1765);
DISPLAY 0.978723 (90 1765);
PAINT SKYBLUE (90 1765);
DISPLAY INVISIBLE (90 1765);
FORCEPROP 1 LAST MATERIAL EMPTY
J 0
(75 1815);
DISPLAY 0.978723 (75 1815);
PAINT RED (75 1815);
DISPLAY INVISIBLE (75 1815);
FORCEPROP 2 LAST CDS_LIB mstr_misc
J 0
(150 1950);
PAINT ORANGE (150 1950);
DISPLAY INVISIBLE (150 1950);
FORCEPROP 0 LAST SEC 1
J 0
(75 2050);
DISPLAY 0.680851 (75 2050);
PAINT MONO (75 2050);
DISPLAY INVISIBLE (75 2050);
FORCEPROP 1 LAST PATH I260
J 0
(100 2050);
DISPLAY 0.978723 (100 2050);
PAINT ORANGE (100 2050);
DISPLAY INVISIBLE (100 2050);
FORCEPROP 2 LAST SEC_TYPE SH0201
J 0
(100 2100);
DISPLAY 1.021277 (100 2100);
PAINT ORANGE (100 2100);
DISPLAY INVISIBLE (100 2100);
FORCEADD RES..2
(4975 -475);
FORCEPROP 1 LASTPIN (4975 -575) $PN 2
J 0
(4980 -565);
DISPLAY 0.617021 (4980 -565);
PAINT GREEN (4980 -565);
FORCEPROP 1 LASTPIN (4975 -375) $PN 1
J 0
(4980 -413);
DISPLAY 0.617021 (4980 -413);
PAINT GREEN (4980 -413);
FORCEPROP 1 LAST TOLERANCE 1%
J 0
(5020 -450);
DISPLAY 0.617021 (5020 -450);
PAINT SKYBLUE (5020 -450);
FORCEPROP 1 LAST WATTAGE 1/10W
J 0
(5015 -500);
DISPLAY 0.617021 (5015 -500);
PAINT SKYBLUE (5015 -500);
FORCEPROP 1 LAST MATERIAL CHIP
J 0
(5015 -550);
DISPLAY 0.617021 (5015 -550);
PAINT SKYBLUE (5015 -550);
FORCEPROP 1 LAST PACK_TYPE 0603
J 0
(5015 -650);
DISPLAY 0.617021 (5015 -650);
PAINT SKYBLUE (5015 -650);
FORCEPROP 1 LAST VALUE 120.0
J 0
(5020 -400);
DISPLAY 0.617021 (5020 -400);
PAINT SKYBLUE (5020 -400);
FORCEPROP 1 LAST PART_NUMBER G22026-003
J 0
(5015 -600);
DISPLAY 0.617021 (5015 -600);
PAINT BLUE (5015 -600);
FORCEPROP 1 LAST LOCATION R3U4
J 0
(5020 -350);
DISPLAY 0.617021 (5020 -350);
PAINT AQUA (5020 -350);
FORCEPROP 2 LAST CDS_LIB mstr_discrete
J 0
(4975 -475);
PAINT ORANGE (4975 -475);
DISPLAY INVISIBLE (4975 -475);
FORCEPROP 2 LAST ROOM VDDQ_ABC_PWR_VR
J 0
(5025 -300);
PAINT MONO (5025 -300);
DISPLAY INVISIBLE (5025 -300);
FORCEPROP 1 LAST PATH I58
J 0
(5025 -300);
DISPLAY 0.978723 (5025 -300);
PAINT GREEN (5025 -300);
DISPLAY INVISIBLE (5025 -300);
FORCEPROP 2 LAST BOM_COST MEM_VRD_PVPP_AB
J 0
(5025 -300);
PAINT MONO (5025 -300);
DISPLAY INVISIBLE (5025 -300);
FORCEPROP 2 LAST CDS_LOCATION R3U4
J 0
(5020 -350);
DISPLAY 0.617021 (5020 -350);
PAINT AQUA (5020 -350);
DISPLAY INVISIBLE (5020 -350);
FORCEPROP 2 LAST $SEC 1
J 0
(5025 -250);
PAINT MONO (5025 -250);
DISPLAY INVISIBLE (5025 -250);
FORCEPROP 2 LAST CDS_SEC 1
J 0
(5025 -250);
PAINT MONO (5025 -250);
DISPLAY INVISIBLE (5025 -250);
FORCEADD GND..1
(400 1275);
FORCEPROP 3 LASTPIN (400 1325) SIG_NAME GND\g
J 0
(410 1335);
DISPLAY 0.659574 (410 1335);
PAINT MONO (410 1335);
DISPLAY INVISIBLE (410 1335);
FORCEPROP 2 LAST ROOM VDDQ_ABC_PWR_VR
J 0
(-150 1350);
PAINT ORANGE (-150 1350);
DISPLAY INVISIBLE (-150 1350);
FORCEPROP 2 LAST BOM_COST MEM_VRD_PVPP_AB
J 0
(75 1350);
PAINT MONO (75 1350);
DISPLAY INVISIBLE (75 1350);
FORCEPROP 1 LAST BODY_TYPE PLUMBING
J 0
(355 1232);
DISPLAY 0.340426 (355 1232);
PAINT GREEN (355 1232);
DISPLAY INVISIBLE (355 1232);
FORCEPROP 1 LAST SIZE 1B
J 0
(475 1225);
DISPLAY 0.893617 (475 1225);
PAINT GREEN (475 1225);
DISPLAY INVISIBLE (475 1225);
FORCEPROP 2 LAST CDS_LIB mstr_symbols
J 0
(400 1275);
PAINT ORANGE (400 1275);
DISPLAY INVISIBLE (400 1275);
FORCEPROP 1 LAST PATH I65
J 0
(475 1275);
DISPLAY 1.170213 (475 1275);
PAINT AQUA (475 1275);
DISPLAY INVISIBLE (475 1275);
FORCEPROP 1 LAST VOLTAGE 0
J 0
(400 1275);
PAINT SKYBLUE (400 1275);
DISPLAY INVISIBLE (400 1275);
FORCEPROP 1 LAST HDL_POWER GND
J 0
(400 1425);
DISPLAY 0.893617 (400 1425);
PAINT GREEN (400 1425);
DISPLAY INVISIBLE (400 1425);
FORCEADD OFFPAGE..1
(-1525 1675);
FORCEPROP 2 LAST $XR0 215 
J 0
(-1777 1675);
DISPLAY 0.638298 (-1777 1675);
PAINT MONO (-1777 1675);
FORCEPROP 2 LAST PATH I70
J 0
(-1455 1745);
DISPLAY 1.361702 (-1455 1745);
PAINT ORANGE (-1455 1745);
DISPLAY INVISIBLE (-1455 1745);
FORCEPROP 1 LAST COMMENT_BODY TRUE
J 0
(-1400 1575);
DISPLAY 0.893617 (-1400 1575);
PAINT GREEN (-1400 1575);
DISPLAY INVISIBLE (-1400 1575);
FORCEPROP 1 LAST OFFPAGE TRUE
J 0
(-1200 1550);
DISPLAY 0.893617 (-1200 1550);
PAINT GREEN (-1200 1550);
DISPLAY INVISIBLE (-1200 1550);
FORCEPROP 2 LAST CDS_LIB mstr_standard
J 0
(-1525 1675);
PAINT ORANGE (-1525 1675);
DISPLAY INVISIBLE (-1525 1675);
FORCEADD OFFPAGE..1
(-1525 1925);
FORCEPROP 2 LAST $XR0 215 
J 0
(-1777 1925);
DISPLAY 0.638298 (-1777 1925);
PAINT MONO (-1777 1925);
FORCEPROP 1 LAST COMMENT_BODY TRUE
J 0
(-1400 1825);
DISPLAY 1.170213 (-1400 1825);
PAINT GREEN (-1400 1825);
DISPLAY INVISIBLE (-1400 1825);
FORCEPROP 1 LAST OFFPAGE TRUE
J 0
(-1200 1800);
DISPLAY 1.170213 (-1200 1800);
PAINT GREEN (-1200 1800);
DISPLAY INVISIBLE (-1200 1800);
FORCEPROP 2 LAST CDS_LIB mstr_standard
J 0
(-1525 1925);
PAINT ORANGE (-1525 1925);
DISPLAY INVISIBLE (-1525 1925);
FORCEPROP 2 LAST PATH I72
J 0
(-1475 2000);
DISPLAY 1.361702 (-1475 2000);
PAINT ORANGE (-1475 2000);
DISPLAY INVISIBLE (-1475 2000);
FORCEADD PVDDQ_ABC..1
(425 2150);
FORCEPROP 3 LASTPIN (425 2100) SIG_NAME PVDDQ_ABC\g
J 0
(435 2110);
DISPLAY 0.659574 (435 2110);
PAINT MONO (435 2110);
DISPLAY INVISIBLE (435 2110);
FORCEPROP 2 LAST BOM_COST MEM_VRD_PVPP_AB
J 0
(450 2250);
PAINT MONO (450 2250);
DISPLAY INVISIBLE (450 2250);
FORCEPROP 2 LAST CDS_LIB mstr_symbols
J 0
(425 2150);
PAINT ORANGE (425 2150);
DISPLAY INVISIBLE (425 2150);
FORCEPROP 1 LAST BODY_TYPE PLUMBING
J 0
(380 2107);
DISPLAY 0.340426 (380 2107);
PAINT GREEN (380 2107);
DISPLAY INVISIBLE (380 2107);
FORCEPROP 1 LAST PATH I73
J 0
(475 2175);
DISPLAY 0.872340 (475 2175);
PAINT AQUA (475 2175);
DISPLAY INVISIBLE (475 2175);
FORCEPROP 1 LAST HDL_POWER PVDDQ_ABC
J 1
(425 2200);
DISPLAY 0.872340 (425 2200);
PAINT GREEN (425 2200);
DISPLAY INVISIBLE (425 2200);
FORCEPROP 1 LAST VOLTAGE 1.2V
J 0
(380 2107);
DISPLAY 0.340426 (380 2107);
PAINT SKYBLUE (380 2107);
DISPLAY INVISIBLE (380 2107);
FORCEPROP 2 LAST ROOM VDDQ_ABC_PWR_VR
J 0
(675 2250);
PAINT ORANGE (675 2250);
DISPLAY INVISIBLE (675 2250);
FORCEADD RES..2
(-250 1700);
FORCEPROP 1 LAST PACK_TYPE 0402
J 0
(-210 1525);
DISPLAY 0.617021 (-210 1525);
PAINT SKYBLUE (-210 1525);
FORCEPROP 1 LASTPIN (-250 1600) $PN 2
J 0
(-245 1610);
DISPLAY 0.617021 (-245 1610);
PAINT ORANGE (-245 1610);
FORCEPROP 1 LASTPIN (-250 1800) $PN 1
J 0
(-245 1762);
DISPLAY 0.617021 (-245 1762);
PAINT ORANGE (-245 1762);
FORCEPROP 1 LAST TOLERANCE 1%
J 0
(-205 1725);
DISPLAY 0.617021 (-205 1725);
PAINT SKYBLUE (-205 1725);
FORCEPROP 1 LAST WATTAGE 1/16W
J 0
(-210 1675);
DISPLAY 0.617021 (-210 1675);
PAINT SKYBLUE (-210 1675);
FORCEPROP 1 LAST MATERIAL EMPTY
J 0
(-210 1625);
DISPLAY 0.617021 (-210 1625);
PAINT RED (-210 1625);
FORCEPROP 1 LAST VALUE 100.0
J 0
(-205 1775);
DISPLAY 0.617021 (-205 1775);
PAINT SKYBLUE (-205 1775);
FORCEPROP 1 LAST LOCATION R4U6
J 0
(-205 1825);
DISPLAY 0.617021 (-205 1825);
PAINT AQUA (-205 1825);
FORCEPROP 1 LAST PART_NUMBER G21796-017
J 0
(-210 1575);
DISPLAY 0.617021 (-210 1575);
PAINT BLUE (-210 1575);
FORCEPROP 2 LAST CDS_LIB mstr_discrete
J 0
(-250 1700);
PAINT ORANGE (-250 1700);
DISPLAY INVISIBLE (-250 1700);
FORCEPROP 2 LAST SEC_TYPE 0402
J 0
(-200 1950);
DISPLAY 1.021277 (-200 1950);
PAINT ORANGE (-200 1950);
DISPLAY INVISIBLE (-200 1950);
FORCEPROP 2 LAST SEC 1
J 0
(-200 1950);
DISPLAY 0.680851 (-200 1950);
PAINT MONO (-200 1950);
DISPLAY INVISIBLE (-200 1950);
FORCEPROP 2 LAST CDS_LOCATION R4U6
J 0
(-205 1825);
DISPLAY 0.617021 (-205 1825);
PAINT AQUA (-205 1825);
DISPLAY INVISIBLE (-205 1825);
FORCEPROP 1 LAST PATH I74
J 0
(-200 1875);
DISPLAY 1.319149 (-200 1875);
PAINT WHITE (-200 1875);
DISPLAY INVISIBLE (-200 1875);
FORCEPROP 0 LAST ROOM VDDQ_ABC_PWR_VR
J 0
(-200 1925);
DISPLAY 1.021277 (-200 1925);
PAINT ORANGE (-200 1925);
DISPLAY INVISIBLE (-200 1925);
FORCEADD CAPP..1
(3375 -450);
FORCEPROP 1 LASTPIN (3375 -550) $PN 2
J 0
(3385 -565);
DISPLAY 0.617021 (3385 -565);
PAINT ORANGE (3385 -565);
FORCEPROP 1 LAST MATERIAL ALUM
J 0
(3425 -550);
DISPLAY 0.617021 (3425 -550);
PAINT SKYBLUE (3425 -550);
FORCEPROP 1 LAST PACK_TYPE 3018
J 0
(3425 -600);
DISPLAY 0.617021 (3425 -600);
PAINT SKYBLUE (3425 -600);
FORCEPROP 1 LASTPIN (3375 -350) $PN 1
J 0
(3385 -365);
DISPLAY 0.617021 (3385 -365);
PAINT ORANGE (3385 -365);
FORCEPROP 1 LAST VOLTAGE 2.5V
J 0
(3425 -500);
DISPLAY 0.617021 (3425 -500);
PAINT SKYBLUE (3425 -500);
FORCEPROP 1 LAST TOLERANCE 20%
J 0
(3425 -450);
DISPLAY 0.617021 (3425 -450);
PAINT SKYBLUE (3425 -450);
FORCEPROP 1 LAST VALUE 470UF
J 0
(3425 -400);
DISPLAY 0.617021 (3425 -400);
PAINT SKYBLUE (3425 -400);
FORCEPROP 1 LAST LOCATION C7G28
J 0
(3425 -350);
DISPLAY 0.617021 (3425 -350);
PAINT AQUA (3425 -350);
FORCEPROP 1 LAST PART_NUMBER 699013-049
J 0
(3425 -650);
DISPLAY 0.617021 (3425 -650);
PAINT BLUE (3425 -650);
FORCEPROP 2 LAST CDS_LIB mstr_discrete
J 0
(3375 -450);
PAINT ORANGE (3375 -450);
DISPLAY INVISIBLE (3375 -450);
FORCEPROP 2 LAST CDS_LOCATION C7G28
J 0
(3425 -350);
DISPLAY 0.617021 (3425 -350);
PAINT AQUA (3425 -350);
DISPLAY INVISIBLE (3425 -350);
FORCEPROP 0 LAST ROOM VDDQ_ABC_PWR_VR
J 0
(3425 -300);
DISPLAY 1.021277 (3425 -300);
PAINT ORANGE (3425 -300);
DISPLAY INVISIBLE (3425 -300);
FORCEPROP 1 LAST PATH I75
J 0
(3425 -300);
DISPLAY 1.319149 (3425 -300);
PAINT ORANGE (3425 -300);
DISPLAY INVISIBLE (3425 -300);
FORCEPROP 2 LAST SEC_TYPE 3018
J 0
(3425 -225);
DISPLAY 1.021277 (3425 -225);
PAINT ORANGE (3425 -225);
DISPLAY INVISIBLE (3425 -225);
FORCEPROP 2 LAST SEC 1
J 0
(3425 -225);
DISPLAY 0.680851 (3425 -225);
PAINT MONO (3425 -225);
DISPLAY INVISIBLE (3425 -225);
FORCEADD CAPP..1
(3800 -450);
FORCEPROP 1 LAST MATERIAL ALUM
J 0
(3850 -550);
DISPLAY 0.617021 (3850 -550);
PAINT SKYBLUE (3850 -550);
FORCEPROP 1 LAST PACK_TYPE 3018
J 0
(3850 -600);
DISPLAY 0.617021 (3850 -600);
PAINT SKYBLUE (3850 -600);
FORCEPROP 1 LASTPIN (3800 -350) $PN 1
J 0
(3810 -365);
DISPLAY 0.617021 (3810 -365);
PAINT ORANGE (3810 -365);
FORCEPROP 1 LAST VOLTAGE 2.5V
J 0
(3850 -500);
DISPLAY 0.617021 (3850 -500);
PAINT SKYBLUE (3850 -500);
FORCEPROP 1 LAST TOLERANCE 20%
J 0
(3850 -450);
DISPLAY 0.617021 (3850 -450);
PAINT SKYBLUE (3850 -450);
FORCEPROP 1 LAST VALUE 470UF
J 0
(3850 -400);
DISPLAY 0.617021 (3850 -400);
PAINT SKYBLUE (3850 -400);
FORCEPROP 1 LAST LOCATION C3U1
J 0
(3850 -350);
DISPLAY 0.617021 (3850 -350);
PAINT AQUA (3850 -350);
FORCEPROP 1 LAST PART_NUMBER 699013-049
J 0
(3850 -650);
DISPLAY 0.617021 (3850 -650);
PAINT BLUE (3850 -650);
FORCEPROP 1 LASTPIN (3800 -550) $PN 2
J 0
(3810 -565);
DISPLAY 0.617021 (3810 -565);
PAINT ORANGE (3810 -565);
FORCEPROP 2 LAST CDS_LIB mstr_discrete
J 0
(3800 -450);
PAINT ORANGE (3800 -450);
DISPLAY INVISIBLE (3800 -450);
FORCEPROP 2 LAST SEC_TYPE 3018
J 0
(3850 -225);
DISPLAY 1.021277 (3850 -225);
PAINT ORANGE (3850 -225);
DISPLAY INVISIBLE (3850 -225);
FORCEPROP 2 LAST SEC 1
J 0
(3850 -225);
DISPLAY 0.680851 (3850 -225);
PAINT MONO (3850 -225);
DISPLAY INVISIBLE (3850 -225);
FORCEPROP 2 LAST CDS_LOCATION C3U1
J 0
(3850 -350);
DISPLAY 0.617021 (3850 -350);
PAINT AQUA (3850 -350);
DISPLAY INVISIBLE (3850 -350);
FORCEPROP 1 LAST PATH I76
J 0
(3850 -300);
DISPLAY 1.319149 (3850 -300);
PAINT ORANGE (3850 -300);
DISPLAY INVISIBLE (3850 -300);
FORCEPROP 0 LAST ROOM VDDQ_ABC_PWR_VR
J 0
(3850 -300);
DISPLAY 1.021277 (3850 -300);
PAINT ORANGE (3850 -300);
DISPLAY INVISIBLE (3850 -300);
FORCEADD CAPP..1
(4225 -450);
FORCEPROP 1 LASTPIN (4225 -550) $PN 2
J 0
(4235 -565);
DISPLAY 0.617021 (4235 -565);
PAINT ORANGE (4235 -565);
FORCEPROP 1 LAST MATERIAL ALUM
J 0
(4275 -550);
DISPLAY 0.617021 (4275 -550);
PAINT SKYBLUE (4275 -550);
FORCEPROP 1 LAST PACK_TYPE 3018
J 0
(4275 -600);
DISPLAY 0.617021 (4275 -600);
PAINT SKYBLUE (4275 -600);
FORCEPROP 1 LAST PART_NUMBER 699013-049
J 0
(4275 -650);
DISPLAY 0.617021 (4275 -650);
PAINT BLUE (4275 -650);
FORCEPROP 1 LASTPIN (4225 -350) $PN 1
J 0
(4235 -365);
DISPLAY 0.617021 (4235 -365);
PAINT ORANGE (4235 -365);
FORCEPROP 1 LAST VOLTAGE 2.5V
J 0
(4275 -500);
DISPLAY 0.617021 (4275 -500);
PAINT SKYBLUE (4275 -500);
FORCEPROP 1 LAST TOLERANCE 20%
J 0
(4275 -450);
DISPLAY 0.617021 (4275 -450);
PAINT SKYBLUE (4275 -450);
FORCEPROP 1 LAST VALUE 470UF
J 0
(4275 -400);
DISPLAY 0.617021 (4275 -400);
PAINT SKYBLUE (4275 -400);
FORCEPROP 1 LAST LOCATION C3U5
J 0
(4275 -350);
DISPLAY 0.617021 (4275 -350);
PAINT AQUA (4275 -350);
FORCEPROP 2 LAST CDS_LIB mstr_discrete
J 0
(4225 -450);
PAINT ORANGE (4225 -450);
DISPLAY INVISIBLE (4225 -450);
FORCEPROP 0 LAST ROOM VDDQ_ABC_PWR_VR
J 0
(4275 -300);
DISPLAY 1.021277 (4275 -300);
PAINT ORANGE (4275 -300);
DISPLAY INVISIBLE (4275 -300);
FORCEPROP 2 LAST CDS_LOCATION C3U5
J 0
(4275 -350);
DISPLAY 0.617021 (4275 -350);
PAINT AQUA (4275 -350);
DISPLAY INVISIBLE (4275 -350);
FORCEPROP 1 LAST PATH I77
J 0
(4275 -300);
DISPLAY 1.319149 (4275 -300);
PAINT ORANGE (4275 -300);
DISPLAY INVISIBLE (4275 -300);
FORCEPROP 2 LAST SEC_TYPE 3018
J 0
(4275 -225);
DISPLAY 1.021277 (4275 -225);
PAINT ORANGE (4275 -225);
DISPLAY INVISIBLE (4275 -225);
FORCEPROP 2 LAST SEC 1
J 0
(4275 -225);
DISPLAY 0.680851 (4275 -225);
PAINT MONO (4275 -225);
DISPLAY INVISIBLE (4275 -225);
FORCEADD CAPP..1
(4625 -475);
FORCEPROP 1 LAST PACK_TYPE 3018
J 0
(4675 -625);
DISPLAY 0.617021 (4675 -625);
PAINT SKYBLUE (4675 -625);
FORCEPROP 1 LAST MATERIAL ALUM
J 0
(4675 -575);
DISPLAY 0.617021 (4675 -575);
PAINT SKYBLUE (4675 -575);
FORCEPROP 1 LASTPIN (4625 -575) $PN 2
J 0
(4635 -590);
DISPLAY 0.617021 (4635 -590);
PAINT ORANGE (4635 -590);
FORCEPROP 1 LAST PART_NUMBER 699013-049
J 0
(4675 -675);
DISPLAY 0.617021 (4675 -675);
PAINT BLUE (4675 -675);
FORCEPROP 1 LAST VOLTAGE 2.5V
J 0
(4675 -525);
DISPLAY 0.617021 (4675 -525);
PAINT SKYBLUE (4675 -525);
FORCEPROP 1 LASTPIN (4625 -375) $PN 1
J 0
(4635 -390);
DISPLAY 0.617021 (4635 -390);
PAINT ORANGE (4635 -390);
FORCEPROP 1 LAST TOLERANCE 20%
J 0
(4675 -475);
DISPLAY 0.617021 (4675 -475);
PAINT SKYBLUE (4675 -475);
FORCEPROP 1 LAST VALUE 470UF
J 0
(4675 -425);
DISPLAY 0.617021 (4675 -425);
PAINT SKYBLUE (4675 -425);
FORCEPROP 1 LAST LOCATION C3U8
J 0
(4675 -375);
DISPLAY 0.617021 (4675 -375);
PAINT AQUA (4675 -375);
FORCEPROP 2 LAST CDS_LIB mstr_discrete
J 0
(4625 -475);
PAINT ORANGE (4625 -475);
DISPLAY INVISIBLE (4625 -475);
FORCEPROP 2 LAST CDS_LOCATION C3U8
J 0
(4675 -375);
DISPLAY 0.617021 (4675 -375);
PAINT AQUA (4675 -375);
DISPLAY INVISIBLE (4675 -375);
FORCEPROP 1 LAST PATH I78
J 0
(4675 -325);
DISPLAY 1.319149 (4675 -325);
PAINT ORANGE (4675 -325);
DISPLAY INVISIBLE (4675 -325);
FORCEPROP 0 LAST ROOM VDDQ_ABC_PWR_VR
J 0
(4675 -325);
DISPLAY 1.021277 (4675 -325);
PAINT ORANGE (4675 -325);
DISPLAY INVISIBLE (4675 -325);
FORCEPROP 2 LAST SEC_TYPE 3018
J 0
(4675 -250);
DISPLAY 1.021277 (4675 -250);
PAINT ORANGE (4675 -250);
DISPLAY INVISIBLE (4675 -250);
FORCEPROP 2 LAST SEC 1
J 0
(4675 -250);
DISPLAY 0.680851 (4675 -250);
PAINT MONO (4675 -250);
DISPLAY INVISIBLE (4675 -250);
FORCEADD PVDDQ_ABC..1
(3375 -150);
FORCEPROP 3 LASTPIN (3375 -200) SIG_NAME PVDDQ_ABC\g
J 0
(3385 -190);
DISPLAY 0.659574 (3385 -190);
PAINT MONO (3385 -190);
DISPLAY INVISIBLE (3385 -190);
FORCEPROP 2 LAST BOM_COST MEM_VRD_PVPP_AB
J 0
(3425 -50);
PAINT MONO (3425 -50);
DISPLAY INVISIBLE (3425 -50);
FORCEPROP 2 LAST CDS_LIB mstr_symbols
J 0
(3375 -150);
PAINT ORANGE (3375 -150);
DISPLAY INVISIBLE (3375 -150);
FORCEPROP 1 LAST BODY_TYPE PLUMBING
J 0
(3330 -193);
DISPLAY 0.340426 (3330 -193);
PAINT GREEN (3330 -193);
DISPLAY INVISIBLE (3330 -193);
FORCEPROP 1 LAST PATH I80
J 0
(3425 -125);
DISPLAY 0.872340 (3425 -125);
PAINT AQUA (3425 -125);
DISPLAY INVISIBLE (3425 -125);
FORCEPROP 1 LAST HDL_POWER PVDDQ_ABC
J 1
(3375 -100);
DISPLAY 0.872340 (3375 -100);
PAINT GREEN (3375 -100);
DISPLAY INVISIBLE (3375 -100);
FORCEPROP 1 LAST VOLTAGE 1.2V
J 0
(3330 -193);
DISPLAY 0.340426 (3330 -193);
PAINT SKYBLUE (3330 -193);
DISPLAY INVISIBLE (3330 -193);
FORCEPROP 2 LAST ROOM VDDQ_ABC_PWR_VR
J 0
(3600 -50);
PAINT ORANGE (3600 -50);
DISPLAY INVISIBLE (3600 -50);
FORCEADD GND..1
(3375 -875);
FORCEPROP 3 LASTPIN (3375 -825) SIG_NAME GND\g
J 0
(3385 -815);
DISPLAY 0.659574 (3385 -815);
PAINT MONO (3385 -815);
DISPLAY INVISIBLE (3385 -815);
FORCEPROP 2 LAST ROOM VDDQ_ABC_PWR_VR
J 0
(2825 -800);
PAINT ORANGE (2825 -800);
DISPLAY INVISIBLE (2825 -800);
FORCEPROP 2 LAST BOM_COST MEM_VRD_PVPP_AB
J 0
(3050 -800);
PAINT MONO (3050 -800);
DISPLAY INVISIBLE (3050 -800);
FORCEPROP 2 LAST CDS_LIB mstr_symbols
J 0
(3375 -875);
PAINT ORANGE (3375 -875);
DISPLAY INVISIBLE (3375 -875);
FORCEPROP 1 LAST SIZE 1B
J 0
(3450 -925);
DISPLAY 0.893617 (3450 -925);
PAINT GREEN (3450 -925);
DISPLAY INVISIBLE (3450 -925);
FORCEPROP 1 LAST BODY_TYPE PLUMBING
J 0
(3330 -918);
DISPLAY 0.340426 (3330 -918);
PAINT GREEN (3330 -918);
DISPLAY INVISIBLE (3330 -918);
FORCEPROP 1 LAST PATH I81
J 0
(3450 -875);
DISPLAY 1.170213 (3450 -875);
PAINT AQUA (3450 -875);
DISPLAY INVISIBLE (3450 -875);
FORCEPROP 1 LAST VOLTAGE 0
J 0
(3375 -875);
PAINT SKYBLUE (3375 -875);
DISPLAY INVISIBLE (3375 -875);
FORCEPROP 1 LAST HDL_POWER GND
J 0
(3375 -725);
DISPLAY 0.893617 (3375 -725);
PAINT GREEN (3375 -725);
DISPLAY INVISIBLE (3375 -725);
FORCEADD CAP..1
(5475 2850);
FORCEPROP 1 LAST MATERIAL X5R
J 0
(5525 2750);
DISPLAY 0.617021 (5525 2750);
PAINT SKYBLUE (5525 2750);
FORCEPROP 1 LASTPIN (5475 2750) $PN 2
J 0
(5485 2730);
DISPLAY 0.617021 (5485 2730);
PAINT ORANGE (5485 2730);
FORCEPROP 1 LAST TOLERANCE 20%
J 0
(5525 2800);
DISPLAY 0.617021 (5525 2800);
PAINT SKYBLUE (5525 2800);
FORCEPROP 1 LASTPIN (5475 2950) $PN 1
J 0
(5485 2930);
DISPLAY 0.617021 (5485 2930);
PAINT ORANGE (5485 2930);
FORCEPROP 1 LAST VOLTAGE 4V
J 0
(5525 2850);
DISPLAY 0.617021 (5525 2850);
PAINT SKYBLUE (5525 2850);
FORCEPROP 1 LAST PACK_TYPE 0805
J 0
(5525 2650);
DISPLAY 0.617021 (5525 2650);
PAINT SKYBLUE (5525 2650);
FORCEPROP 1 LAST VALUE 100UF
J 0
(5525 2900);
DISPLAY 0.617021 (5525 2900);
PAINT SKYBLUE (5525 2900);
FORCEPROP 1 LAST PART_NUMBER 602433-112
J 0
(5525 2700);
DISPLAY 0.617021 (5525 2700);
PAINT BLUE (5525 2700);
FORCEPROP 1 LAST LOCATION C5U13
J 0
(5525 2950);
DISPLAY 0.617021 (5525 2950);
PAINT AQUA (5525 2950);
FORCEPROP 2 LAST CDS_LIB mstr_discrete
J 0
(5475 2850);
PAINT MONO (5475 2850);
DISPLAY INVISIBLE (5475 2850);
FORCEPROP 2 LAST ROOM VDDQ_ABC_PWR_VR
J 0
(5525 3000);
PAINT MONO (5525 3000);
DISPLAY INVISIBLE (5525 3000);
FORCEPROP 1 LAST PATH I82
J 0
(5525 3000);
DISPLAY 0.978723 (5525 3000);
PAINT WHITE (5525 3000);
DISPLAY INVISIBLE (5525 3000);
FORCEPROP 2 LAST CDS_LOCATION C5U13
J 0
(5525 2950);
DISPLAY 0.617021 (5525 2950);
PAINT AQUA (5525 2950);
DISPLAY INVISIBLE (5525 2950);
FORCEPROP 2 LAST BOM_COST MEM_VRD_PVDDQ_CD
J 0
(5525 3000);
PAINT MONO (5525 3000);
DISPLAY INVISIBLE (5525 3000);
FORCEPROP 2 LAST SEC_TYPE 0805
J 0
(5525 3050);
DISPLAY 1.021277 (5525 3050);
PAINT ORANGE (5525 3050);
DISPLAY INVISIBLE (5525 3050);
FORCEPROP 2 LAST SEC 1
J 0
(5525 3050);
DISPLAY 0.680851 (5525 3050);
PAINT MONO (5525 3050);
DISPLAY INVISIBLE (5525 3050);
FORCEADD CAP..1
(5075 2850);
FORCEPROP 1 LASTPIN (5075 2750) $PN 2
J 0
(5085 2730);
DISPLAY 0.617021 (5085 2730);
PAINT ORANGE (5085 2730);
FORCEPROP 1 LASTPIN (5075 2950) $PN 1
J 0
(5085 2930);
DISPLAY 0.617021 (5085 2930);
PAINT ORANGE (5085 2930);
FORCEPROP 1 LAST MATERIAL X5R
J 0
(5125 2750);
DISPLAY 0.617021 (5125 2750);
PAINT SKYBLUE (5125 2750);
FORCEPROP 1 LAST VOLTAGE 4V
J 0
(5125 2850);
DISPLAY 0.617021 (5125 2850);
PAINT SKYBLUE (5125 2850);
FORCEPROP 1 LAST PACK_TYPE 0805
J 0
(5125 2650);
DISPLAY 0.617021 (5125 2650);
PAINT SKYBLUE (5125 2650);
FORCEPROP 1 LAST TOLERANCE 20%
J 0
(5125 2800);
DISPLAY 0.617021 (5125 2800);
PAINT SKYBLUE (5125 2800);
FORCEPROP 1 LAST VALUE 100UF
J 0
(5125 2900);
DISPLAY 0.617021 (5125 2900);
PAINT SKYBLUE (5125 2900);
FORCEPROP 1 LAST LOCATION C5U10
J 0
(5125 2950);
DISPLAY 0.617021 (5125 2950);
PAINT AQUA (5125 2950);
FORCEPROP 1 LAST PART_NUMBER 602433-112
J 0
(5125 2700);
DISPLAY 0.617021 (5125 2700);
PAINT BLUE (5125 2700);
FORCEPROP 2 LAST CDS_LIB mstr_discrete
J 0
(5075 2850);
PAINT MONO (5075 2850);
DISPLAY INVISIBLE (5075 2850);
FORCEPROP 2 LAST BOM_COST MEM_VRD_PVDDQ_CD
J 0
(5125 3000);
PAINT MONO (5125 3000);
DISPLAY INVISIBLE (5125 3000);
FORCEPROP 2 LAST CDS_LOCATION C5U10
J 0
(5125 2950);
DISPLAY 0.617021 (5125 2950);
PAINT AQUA (5125 2950);
DISPLAY INVISIBLE (5125 2950);
FORCEPROP 1 LAST PATH I83
J 0
(5125 3000);
DISPLAY 0.978723 (5125 3000);
PAINT WHITE (5125 3000);
DISPLAY INVISIBLE (5125 3000);
FORCEPROP 2 LAST ROOM VDDQ_ABC_PWR_VR
J 0
(5125 3000);
PAINT MONO (5125 3000);
DISPLAY INVISIBLE (5125 3000);
FORCEPROP 2 LAST SEC_TYPE 0805
J 0
(5125 3050);
DISPLAY 1.021277 (5125 3050);
PAINT ORANGE (5125 3050);
DISPLAY INVISIBLE (5125 3050);
FORCEPROP 2 LAST SEC 1
J 0
(5125 3050);
DISPLAY 0.680851 (5125 3050);
PAINT MONO (5125 3050);
DISPLAY INVISIBLE (5125 3050);
FORCEADD CAP..1
(4725 2850);
FORCEPROP 1 LAST MATERIAL X5R
J 0
(4775 2750);
DISPLAY 0.617021 (4775 2750);
PAINT SKYBLUE (4775 2750);
FORCEPROP 1 LASTPIN (4725 2750) $PN 2
J 0
(4735 2730);
DISPLAY 0.617021 (4735 2730);
PAINT ORANGE (4735 2730);
FORCEPROP 1 LAST TOLERANCE 20%
J 0
(4775 2800);
DISPLAY 0.617021 (4775 2800);
PAINT SKYBLUE (4775 2800);
FORCEPROP 1 LASTPIN (4725 2950) $PN 1
J 0
(4735 2930);
DISPLAY 0.617021 (4735 2930);
PAINT ORANGE (4735 2930);
FORCEPROP 1 LAST VOLTAGE 4V
J 0
(4775 2850);
DISPLAY 0.617021 (4775 2850);
PAINT SKYBLUE (4775 2850);
FORCEPROP 1 LAST PACK_TYPE 0805
J 0
(4775 2650);
DISPLAY 0.617021 (4775 2650);
PAINT SKYBLUE (4775 2650);
FORCEPROP 1 LAST VALUE 100UF
J 0
(4775 2900);
DISPLAY 0.617021 (4775 2900);
PAINT SKYBLUE (4775 2900);
FORCEPROP 1 LAST PART_NUMBER 602433-112
J 0
(4775 2700);
DISPLAY 0.617021 (4775 2700);
PAINT BLUE (4775 2700);
FORCEPROP 1 LAST LOCATION C5U1
J 0
(4775 2950);
DISPLAY 0.617021 (4775 2950);
PAINT AQUA (4775 2950);
FORCEPROP 2 LAST CDS_LIB mstr_discrete
J 0
(4725 2850);
PAINT MONO (4725 2850);
DISPLAY INVISIBLE (4725 2850);
FORCEPROP 2 LAST ROOM VDDQ_ABC_PWR_VR
J 0
(4775 3000);
PAINT MONO (4775 3000);
DISPLAY INVISIBLE (4775 3000);
FORCEPROP 1 LAST PATH I88
J 0
(4775 3000);
DISPLAY 0.978723 (4775 3000);
PAINT WHITE (4775 3000);
DISPLAY INVISIBLE (4775 3000);
FORCEPROP 2 LAST CDS_LOCATION C5U1
J 0
(4775 2950);
DISPLAY 0.617021 (4775 2950);
PAINT AQUA (4775 2950);
DISPLAY INVISIBLE (4775 2950);
FORCEPROP 2 LAST BOM_COST MEM_VRD_PVDDQ_CD
J 0
(4775 3000);
PAINT MONO (4775 3000);
DISPLAY INVISIBLE (4775 3000);
FORCEPROP 2 LAST SEC_TYPE 0805
J 0
(4775 3050);
DISPLAY 1.021277 (4775 3050);
PAINT ORANGE (4775 3050);
DISPLAY INVISIBLE (4775 3050);
FORCEPROP 2 LAST SEC 1
J 0
(4775 3050);
DISPLAY 0.680851 (4775 3050);
PAINT MONO (4775 3050);
DISPLAY INVISIBLE (4775 3050);
FORCEADD CAP..1
(4325 2850);
FORCEPROP 1 LASTPIN (4325 2750) $PN 2
J 0
(4335 2730);
DISPLAY 0.617021 (4335 2730);
PAINT ORANGE (4335 2730);
FORCEPROP 1 LASTPIN (4325 2950) $PN 1
J 0
(4335 2930);
DISPLAY 0.617021 (4335 2930);
PAINT ORANGE (4335 2930);
FORCEPROP 1 LAST TOLERANCE 20%
J 0
(4375 2800);
DISPLAY 0.617021 (4375 2800);
PAINT SKYBLUE (4375 2800);
FORCEPROP 1 LAST PACK_TYPE 0805
J 0
(4375 2650);
DISPLAY 0.617021 (4375 2650);
PAINT SKYBLUE (4375 2650);
FORCEPROP 1 LAST VOLTAGE 4V
J 0
(4375 2850);
DISPLAY 0.617021 (4375 2850);
PAINT SKYBLUE (4375 2850);
FORCEPROP 1 LAST MATERIAL X5R
J 0
(4375 2750);
DISPLAY 0.617021 (4375 2750);
PAINT SKYBLUE (4375 2750);
FORCEPROP 1 LAST VALUE 100UF
J 0
(4375 2900);
DISPLAY 0.617021 (4375 2900);
PAINT SKYBLUE (4375 2900);
FORCEPROP 1 LAST LOCATION C5U14
J 0
(4375 2950);
DISPLAY 0.617021 (4375 2950);
PAINT AQUA (4375 2950);
FORCEPROP 1 LAST PART_NUMBER 602433-112
J 0
(4375 2700);
DISPLAY 0.617021 (4375 2700);
PAINT BLUE (4375 2700);
FORCEPROP 2 LAST CDS_LIB mstr_discrete
J 0
(4325 2850);
PAINT MONO (4325 2850);
DISPLAY INVISIBLE (4325 2850);
FORCEPROP 2 LAST BOM_COST MEM_VRD_PVDDQ_CD
J 0
(4375 3000);
PAINT MONO (4375 3000);
DISPLAY INVISIBLE (4375 3000);
FORCEPROP 2 LAST CDS_LOCATION C5U14
J 0
(4375 2950);
DISPLAY 0.617021 (4375 2950);
PAINT AQUA (4375 2950);
DISPLAY INVISIBLE (4375 2950);
FORCEPROP 1 LAST PATH I89
J 0
(4375 3000);
DISPLAY 0.978723 (4375 3000);
PAINT WHITE (4375 3000);
DISPLAY INVISIBLE (4375 3000);
FORCEPROP 2 LAST ROOM VDDQ_ABC_PWR_VR
J 0
(4375 3000);
PAINT MONO (4375 3000);
DISPLAY INVISIBLE (4375 3000);
FORCEPROP 2 LAST SEC_TYPE 0805
J 0
(4375 3050);
DISPLAY 1.021277 (4375 3050);
PAINT ORANGE (4375 3050);
DISPLAY INVISIBLE (4375 3050);
FORCEPROP 2 LAST SEC 1
J 0
(4375 3050);
DISPLAY 0.680851 (4375 3050);
PAINT MONO (4375 3050);
DISPLAY INVISIBLE (4375 3050);
FORCEADD CAP..1
(3975 2850);
FORCEPROP 1 LASTPIN (3975 2750) $PN 2
J 0
(3985 2730);
DISPLAY 0.617021 (3985 2730);
PAINT ORANGE (3985 2730);
FORCEPROP 1 LAST VOLTAGE 4V
J 0
(4025 2850);
DISPLAY 0.617021 (4025 2850);
PAINT SKYBLUE (4025 2850);
FORCEPROP 1 LASTPIN (3975 2950) $PN 1
J 0
(3985 2930);
DISPLAY 0.617021 (3985 2930);
PAINT ORANGE (3985 2930);
FORCEPROP 1 LAST MATERIAL X5R
J 0
(4025 2750);
DISPLAY 0.617021 (4025 2750);
PAINT SKYBLUE (4025 2750);
FORCEPROP 1 LAST PACK_TYPE 0805
J 0
(4025 2650);
DISPLAY 0.617021 (4025 2650);
PAINT SKYBLUE (4025 2650);
FORCEPROP 1 LAST TOLERANCE 20%
J 0
(4025 2800);
DISPLAY 0.617021 (4025 2800);
PAINT SKYBLUE (4025 2800);
FORCEPROP 1 LAST VALUE 100UF
J 0
(4025 2900);
DISPLAY 0.617021 (4025 2900);
PAINT SKYBLUE (4025 2900);
FORCEPROP 1 LAST PART_NUMBER 602433-112
J 0
(4025 2700);
DISPLAY 0.617021 (4025 2700);
PAINT BLUE (4025 2700);
FORCEPROP 1 LAST LOCATION C5U15
J 0
(4025 2950);
DISPLAY 0.617021 (4025 2950);
PAINT AQUA (4025 2950);
FORCEPROP 2 LAST CDS_LIB mstr_discrete
J 0
(3975 2850);
PAINT MONO (3975 2850);
DISPLAY INVISIBLE (3975 2850);
FORCEPROP 2 LAST ROOM VDDQ_ABC_PWR_VR
J 0
(4025 3000);
PAINT MONO (4025 3000);
DISPLAY INVISIBLE (4025 3000);
FORCEPROP 1 LAST PATH I90
J 0
(4025 3000);
DISPLAY 0.978723 (4025 3000);
PAINT WHITE (4025 3000);
DISPLAY INVISIBLE (4025 3000);
FORCEPROP 2 LAST CDS_LOCATION C5U15
J 0
(4025 2950);
DISPLAY 0.617021 (4025 2950);
PAINT AQUA (4025 2950);
DISPLAY INVISIBLE (4025 2950);
FORCEPROP 2 LAST BOM_COST MEM_VRD_PVDDQ_CD
J 0
(4025 3000);
PAINT MONO (4025 3000);
DISPLAY INVISIBLE (4025 3000);
FORCEPROP 2 LAST SEC_TYPE 0805
J 0
(4025 3050);
DISPLAY 1.021277 (4025 3050);
PAINT ORANGE (4025 3050);
DISPLAY INVISIBLE (4025 3050);
FORCEPROP 2 LAST SEC 1
J 0
(4025 3050);
DISPLAY 0.680851 (4025 3050);
PAINT MONO (4025 3050);
DISPLAY INVISIBLE (4025 3050);
FORCEADD CAP..1
(3625 2850);
FORCEPROP 1 LAST PACK_TYPE 0805
J 0
(3675 2650);
DISPLAY 0.617021 (3675 2650);
PAINT SKYBLUE (3675 2650);
FORCEPROP 1 LAST MATERIAL X5R
J 0
(3675 2750);
DISPLAY 0.617021 (3675 2750);
PAINT SKYBLUE (3675 2750);
FORCEPROP 1 LASTPIN (3625 2750) $PN 2
J 0
(3635 2730);
DISPLAY 0.617021 (3635 2730);
PAINT ORANGE (3635 2730);
FORCEPROP 1 LAST TOLERANCE 20%
J 0
(3675 2800);
DISPLAY 0.617021 (3675 2800);
PAINT SKYBLUE (3675 2800);
FORCEPROP 1 LASTPIN (3625 2950) $PN 1
J 0
(3635 2930);
DISPLAY 0.617021 (3635 2930);
PAINT ORANGE (3635 2930);
FORCEPROP 1 LAST VOLTAGE 4V
J 0
(3675 2850);
DISPLAY 0.617021 (3675 2850);
PAINT SKYBLUE (3675 2850);
FORCEPROP 1 LAST VALUE 100UF
J 0
(3675 2900);
DISPLAY 0.617021 (3675 2900);
PAINT SKYBLUE (3675 2900);
FORCEPROP 1 LAST LOCATION C4T4
J 0
(3675 2950);
DISPLAY 0.617021 (3675 2950);
PAINT AQUA (3675 2950);
FORCEPROP 1 LAST PART_NUMBER 602433-112
J 0
(3675 2700);
DISPLAY 0.617021 (3675 2700);
PAINT BLUE (3675 2700);
FORCEPROP 2 LAST CDS_LIB mstr_discrete
J 0
(3625 2850);
PAINT MONO (3625 2850);
DISPLAY INVISIBLE (3625 2850);
FORCEPROP 2 LAST BOM_COST MEM_VRD_PVDDQ_CD
J 0
(3675 3000);
PAINT MONO (3675 3000);
DISPLAY INVISIBLE (3675 3000);
FORCEPROP 2 LAST CDS_LOCATION C4T4
J 0
(3675 2950);
DISPLAY 0.617021 (3675 2950);
PAINT AQUA (3675 2950);
DISPLAY INVISIBLE (3675 2950);
FORCEPROP 1 LAST PATH I91
J 0
(3675 3000);
DISPLAY 0.978723 (3675 3000);
PAINT WHITE (3675 3000);
DISPLAY INVISIBLE (3675 3000);
FORCEPROP 2 LAST ROOM VDDQ_ABC_PWR_VR
J 0
(3675 3000);
PAINT MONO (3675 3000);
DISPLAY INVISIBLE (3675 3000);
FORCEPROP 2 LAST SEC_TYPE 0805
J 0
(3675 3050);
DISPLAY 1.021277 (3675 3050);
PAINT ORANGE (3675 3050);
DISPLAY INVISIBLE (3675 3050);
FORCEPROP 2 LAST SEC 1
J 0
(3675 3050);
DISPLAY 0.680851 (3675 3050);
PAINT MONO (3675 3050);
DISPLAY INVISIBLE (3675 3050);
FORCEADD CAP..1
(3225 2850);
FORCEPROP 1 LASTPIN (3225 2750) $PN 2
J 0
(3235 2730);
DISPLAY 0.617021 (3235 2730);
PAINT ORANGE (3235 2730);
FORCEPROP 1 LASTPIN (3225 2950) $PN 1
J 0
(3235 2930);
DISPLAY 0.617021 (3235 2930);
PAINT ORANGE (3235 2930);
FORCEPROP 1 LAST MATERIAL X5R
J 0
(3275 2750);
DISPLAY 0.617021 (3275 2750);
PAINT SKYBLUE (3275 2750);
FORCEPROP 1 LAST VOLTAGE 4V
J 0
(3275 2850);
DISPLAY 0.617021 (3275 2850);
PAINT SKYBLUE (3275 2850);
FORCEPROP 1 LAST PACK_TYPE 0805
J 0
(3275 2650);
DISPLAY 0.617021 (3275 2650);
PAINT SKYBLUE (3275 2650);
FORCEPROP 1 LAST TOLERANCE 20%
J 0
(3275 2800);
DISPLAY 0.617021 (3275 2800);
PAINT SKYBLUE (3275 2800);
FORCEPROP 1 LAST VALUE 100UF
J 0
(3275 2900);
DISPLAY 0.617021 (3275 2900);
PAINT SKYBLUE (3275 2900);
FORCEPROP 1 LAST PART_NUMBER 602433-112
J 0
(3275 2700);
DISPLAY 0.617021 (3275 2700);
PAINT BLUE (3275 2700);
FORCEPROP 1 LAST LOCATION C5G9
J 0
(3275 2950);
DISPLAY 0.617021 (3275 2950);
PAINT AQUA (3275 2950);
FORCEPROP 2 LAST CDS_LIB mstr_discrete
J 0
(3225 2850);
PAINT MONO (3225 2850);
DISPLAY INVISIBLE (3225 2850);
FORCEPROP 2 LAST ROOM VDDQ_ABC_PWR_VR
J 0
(3275 3000);
PAINT MONO (3275 3000);
DISPLAY INVISIBLE (3275 3000);
FORCEPROP 1 LAST PATH I92
J 0
(3275 3000);
DISPLAY 0.978723 (3275 3000);
PAINT WHITE (3275 3000);
DISPLAY INVISIBLE (3275 3000);
FORCEPROP 2 LAST CDS_LOCATION C5G9
J 0
(3275 2950);
DISPLAY 0.617021 (3275 2950);
PAINT AQUA (3275 2950);
DISPLAY INVISIBLE (3275 2950);
FORCEPROP 2 LAST BOM_COST MEM_VRD_PVDDQ_CD
J 0
(3275 3000);
PAINT MONO (3275 3000);
DISPLAY INVISIBLE (3275 3000);
FORCEPROP 2 LAST SEC_TYPE 0805
J 0
(3275 3050);
DISPLAY 1.021277 (3275 3050);
PAINT ORANGE (3275 3050);
DISPLAY INVISIBLE (3275 3050);
FORCEPROP 2 LAST SEC 1
J 0
(3275 3050);
DISPLAY 0.680851 (3275 3050);
PAINT MONO (3275 3050);
DISPLAY INVISIBLE (3275 3050);
FORCEADD PVDDQ_ABC..1
(2875 3125);
FORCEPROP 3 LASTPIN (2875 3075) SIG_NAME PVDDQ_ABC\g
J 0
(2885 3085);
DISPLAY 0.659574 (2885 3085);
PAINT MONO (2885 3085);
DISPLAY INVISIBLE (2885 3085);
FORCEPROP 2 LAST BOM_COST MEM_VRD_PVDDQ_CD
J 0
(2950 3225);
PAINT MONO (2950 3225);
DISPLAY INVISIBLE (2950 3225);
FORCEPROP 2 LAST CDS_LIB mstr_symbols
J 0
(2875 3125);
PAINT ORANGE (2875 3125);
DISPLAY INVISIBLE (2875 3125);
FORCEPROP 1 LAST BODY_TYPE PLUMBING
J 0
(2830 3082);
DISPLAY 0.340426 (2830 3082);
PAINT GREEN (2830 3082);
DISPLAY INVISIBLE (2830 3082);
FORCEPROP 1 LAST PATH I93
J 0
(2925 3150);
DISPLAY 0.872340 (2925 3150);
PAINT AQUA (2925 3150);
DISPLAY INVISIBLE (2925 3150);
FORCEPROP 1 LAST HDL_POWER PVDDQ_ABC
J 1
(2875 3175);
DISPLAY 0.872340 (2875 3175);
PAINT GREEN (2875 3175);
DISPLAY INVISIBLE (2875 3175);
FORCEPROP 1 LAST VOLTAGE 1.2V
J 0
(2830 3082);
DISPLAY 0.340426 (2830 3082);
PAINT SKYBLUE (2830 3082);
DISPLAY INVISIBLE (2830 3082);
FORCEPROP 2 LAST ROOM VDDQ_ABC_PWR_VR
J 0
(3125 3225);
PAINT ORANGE (3125 3225);
DISPLAY INVISIBLE (3125 3225);
FORCEADD GND..1
(4600 2475);
FORCEPROP 3 LASTPIN (4600 2525) SIG_NAME GND\g
J 0
(4610 2535);
DISPLAY 0.659574 (4610 2535);
PAINT MONO (4610 2535);
DISPLAY INVISIBLE (4610 2535);
FORCEPROP 2 LAST ROOM VDDQ_ABC_PWR_VR
J 0
(4050 2550);
PAINT ORANGE (4050 2550);
DISPLAY INVISIBLE (4050 2550);
FORCEPROP 2 LAST CDS_LIB mstr_symbols
J 0
(4600 2475);
PAINT ORANGE (4600 2475);
DISPLAY INVISIBLE (4600 2475);
FORCEPROP 1 LAST BODY_TYPE PLUMBING
J 0
(4555 2432);
DISPLAY 0.340426 (4555 2432);
PAINT GREEN (4555 2432);
DISPLAY INVISIBLE (4555 2432);
FORCEPROP 1 LAST VOLTAGE 0
J 0
(4600 2475);
PAINT SKYBLUE (4600 2475);
DISPLAY INVISIBLE (4600 2475);
FORCEPROP 2 LAST BOM_COST MEM_VRD_PVDDQ_CD
J 0
(4275 2550);
PAINT MONO (4275 2550);
DISPLAY INVISIBLE (4275 2550);
FORCEPROP 1 LAST HDL_POWER GND
J 0
(4600 2625);
DISPLAY 0.893617 (4600 2625);
PAINT GREEN (4600 2625);
DISPLAY INVISIBLE (4600 2625);
FORCEPROP 1 LAST SIZE 1B
J 0
(4675 2425);
DISPLAY 0.893617 (4675 2425);
PAINT GREEN (4675 2425);
DISPLAY INVISIBLE (4675 2425);
FORCEPROP 1 LAST PATH I94
J 0
(4675 2475);
DISPLAY 1.170213 (4675 2475);
PAINT AQUA (4675 2475);
DISPLAY INVISIBLE (4675 2475);
FORCEADD DNS..2
(-245 1695);
PAINT RED (-245 1695);
FORCEPROP 1 LAST COMMENT_BODY TRUE
R 1
J 0
(-170 1470);
DISPLAY 0.872340 (-170 1470);
PAINT GREEN (-170 1470);
DISPLAY INVISIBLE (-170 1470);
FORCEPROP 2 LAST CDS_LIB mstr_misc
J 0
(-245 1695);
PAINT ORANGE (-245 1695);
DISPLAY INVISIBLE (-245 1695);
FORCEADD DNS..3
(155 1945);
PAINT RED (155 1945);
FORCEPROP 1 LAST COMMENT_BODY TRUE
R 1
J 0
(230 1720);
DISPLAY 0.872340 (230 1720);
PAINT GREEN (230 1720);
DISPLAY INVISIBLE (230 1720);
FORCEPROP 2 LAST CDS_LIB mstr_misc
J 0
(155 1945);
PAINT ORANGE (155 1945);
DISPLAY INVISIBLE (155 1945);
FORCEADD DNS..3
(130 1495);
PAINT RED (130 1495);
FORCEPROP 1 LAST COMMENT_BODY TRUE
R 1
J 0
(205 1270);
DISPLAY 0.872340 (205 1270);
PAINT GREEN (205 1270);
DISPLAY INVISIBLE (205 1270);
FORCEPROP 2 LAST CDS_LIB mstr_misc
J 0
(130 1495);
PAINT ORANGE (130 1495);
DISPLAY INVISIBLE (130 1495);
FORCEADD INTEL_CORP_BPAGE..1
(5975 -1500);
FORCEPROP 1 LAST CDS_CON_LAST_MODIFIED Tue Dec 01 11:52:25 2015
J 0
(4550 -1175);
PAINT GREEN (4550 -1175);
DISPLAY INVISIBLE (4550 -1175);
FORCEPROP 1 LAST CUSTOM_TXT_CDS <CURRENT_DESIGN_SHEET> OF <TOTAL_DESIGN_SHEETS>
J 0
(5475 -1475);
PAINT GREEN (5475 -1475);
FORCEPROP 2 LAST CUSTOM_TXT_CDS <XR_PAGE_TITLE>
J 0
(-1915 3750);
DISPLAY 0.638298 (-1915 3750);
PAINT PINK (-1915 3750);
DISPLAY INVISIBLE (-1915 3750);
FORCEPROP 2 LAST CUSTOM_TXT_CDS <CON_LAST_MODIFIED>
J 0
(5025 -1150);
PAINT GREEN (5025 -1150);
FORCEPROP 2 LAST CUSTOM_TXT_CDS <CON_PAGE_NUM> OF <CON_TOTAL_PAGES>
J 0
(5475 -1475);
PAINT GREEN (5475 -1475);
FORCEPROP 1 LAST SCH_TITLE VDDQ ABC DECAP (3 OF 3)
J 0
(-1975 -1450);
DISPLAY 1.212766 (-1975 -1450);
PAINT GREEN (-1975 -1450);
FORCEPROP 1 LAST SCH_ADDRESS1 2200 Mission College Blvd.
J 0
(2000 -1375);
DISPLAY 0.617021 (2000 -1375);
PAINT GREEN (2000 -1375);
FORCEPROP 1 LAST SCH_ADDRESS3 Santa Clara, CA 95052-8119
J 0
(2000 -1475);
DISPLAY 0.617021 (2000 -1475);
PAINT GREEN (2000 -1475);
FORCEPROP 1 LAST SCH_ADDRESS2 P.O. BOX 58119
J 0
(2000 -1425);
DISPLAY 0.617021 (2000 -1425);
PAINT GREEN (2000 -1425);
FORCEPROP 1 LAST SCH_NUMBER H4694802
J 0
(4675 -1350);
DISPLAY 1.212766 (4675 -1350);
PAINT YELLOW (4675 -1350);
FORCEPROP 1 LAST SCH_DEPT BESD
J 1
(1525 -1400);
DISPLAY 1.212766 (1525 -1400);
PAINT YELLOW (1525 -1400);
FORCEPROP 1 LAST SCH_REV 2.420
J 0
(5725 -1350);
DISPLAY 0.978723 (5725 -1350);
PAINT YELLOW (5725 -1350);
FORCEPROP 2 LAST ROOM VDDQ_ABC_PWR_VR
J 0
(-2125 3600);
PAINT ORANGE (-2125 3600);
DISPLAY INVISIBLE (-2125 3600);
FORCEPROP 2 LAST PAGE_BORDER TRUE
J 0
(-1915 3750);
DISPLAY 0.851064 (-1915 3750);
PAINT PINK (-1915 3750);
DISPLAY INVISIBLE (-1915 3750);
FORCEPROP 2 LAST CDS_LIB mstr_symbols
J 0
(5975 -1500);
PAINT ORANGE (5975 -1500);
DISPLAY INVISIBLE (5975 -1500);
FORCEPROP 1 LAST COMMENT_BODY TRUE
J 0
(5987 -1488);
DISPLAY 0.446809 (5987 -1488);
PAINT GREEN (5987 -1488);
DISPLAY INVISIBLE (5987 -1488);
FORCEPROP 2 LAST CDS_XR_PAGE_TITLE CR-217 : @BASEBOARD_FAB2_LIB.BASEBOARD_FAB2(SCH_1):PAGE217
J 0
(-1915 3750);
DISPLAY 0.638298 (-1915 3750);
PAINT PINK (-1915 3750);
DISPLAY INVISIBLE (-1915 3750);
WIRE 16 -1 (4750 1825)(4750 1900);
WIRE 16 -1 (4750 1900)(4350 1900);
WIRE 16 -1 (4350 1825)(4350 1900);
WIRE 16 -1 (4350 1900)(4000 1900);
WIRE 16 -1 (4000 1825)(4000 1900);
WIRE 16 -1 (4000 1900)(3650 1900);
WIRE 16 -1 (3650 1825)(3650 1900);
WIRE 16 -1 (3650 1900)(3250 1900);
WIRE 16 -1 (3250 1825)(3250 1900);
WIRE 16 -1 (2900 1900)(3250 1900);
WIRE 16 -1 (2900 1900)(2900 1950);
WIRE 16 -1 (2900 1900)(2900 1825);
WIRE 16 -1 (2900 1625)(2900 1475);
WIRE 16 -1 (2900 1475)(3250 1475);
WIRE 16 -1 (3250 1625)(3250 1475);
WIRE 16 -1 (3250 1475)(3650 1475);
WIRE 16 -1 (3650 1625)(3650 1475);
WIRE 16 -1 (3650 1475)(4000 1475);
WIRE 16 -1 (4000 1625)(4000 1475);
WIRE 16 -1 (4000 1475)(4350 1475);
WIRE 16 -1 (4350 1625)(4350 1475);
WIRE 16 -1 (4625 1475)(4350 1475);
WIRE 16 -1 (4625 1475)(4750 1475);
WIRE 16 -1 (4625 1400)(4625 1475);
WIRE 16 -1 (4750 1625)(4750 1475);
WIRE 16 -1 (200 800)(200 900);
WIRE 16 -1 (200 900)(200 1100);
WIRE 16 -1 (-125 900)(200 900);
WIRE 16 -1 (200 600)(200 525);
WIRE 16 -1 (-325 900)(-550 900);
WIRE 16 -1 (-550 1100)(-550 900);
WIRE 16 -1 (-900 2750)(-900 2600);
WIRE 16 -1 (-900 2600)(-550 2600);
WIRE 16 -1 (-550 2750)(-550 2600);
WIRE 16 -1 (-550 2600)(-200 2600);
WIRE 16 -1 (-200 2750)(-200 2600);
WIRE 16 -1 (-200 2600)(150 2600);
WIRE 16 -1 (150 2725)(150 2600);
WIRE 16 -1 (150 2575)(150 2600);
WIRE 16 -1 (-1300 2950)(-1300 3025);
WIRE 16 -1 (-1650 3025)(-1300 3025);
WIRE 16 -1 (-1650 3025)(-1650 3075);
WIRE 16 -1 (-1650 3025)(-1650 2950);
WIRE 16 -1 (3675 1100)(3675 1175);
WIRE 16 -1 (3675 1175)(3275 1175);
WIRE 16 -1 (3275 1100)(3275 1175);
WIRE 16 -1 (2925 1175)(3275 1175);
WIRE 16 -1 (2925 1175)(2925 1100);
WIRE 16 -1 (2925 1175)(2925 1225);
WIRE 16 -1 (2925 900)(2925 750);
WIRE 16 -1 (2925 750)(3275 750);
WIRE 16 -1 (3275 900)(3275 750);
WIRE 16 -1 (3275 750)(3575 750);
WIRE 16 -1 (3575 750)(3675 750);
WIRE 16 -1 (3575 675)(3575 750);
WIRE 16 -1 (3675 900)(3675 750);
WIRE 16 -1 (150 2925)(150 3025);
WIRE 16 -1 (150 3025)(-200 3025);
WIRE 16 -1 (-200 2950)(-200 3025);
WIRE 16 -1 (-200 3025)(-550 3025);
WIRE 16 -1 (-550 2950)(-550 3025);
WIRE 16 -1 (-550 3025)(-900 3025);
WIRE 16 -1 (-900 2950)(-900 3025);
WIRE 16 -1 (-900 3025)(-900 3075);
WIRE 16 -1 (-1650 2750)(-1650 2600);
WIRE 16 -1 (-1650 2600)(-1300 2600);
WIRE 16 -1 (-1300 2750)(-1300 2600);
WIRE 16 -1 (-1300 2550)(-1300 2600);
WIRE 16 -1 (2550 150)(2550 200);
WIRE 16 -1 (2550 200)(2275 200);
WIRE 16 -1 (2275 150)(2275 200);
WIRE 16 -1 (2275 200)(1975 200);
WIRE 16 -1 (1975 150)(1975 200);
WIRE 16 -1 (1975 200)(1675 200);
WIRE 16 -1 (1675 150)(1675 200);
WIRE 16 -1 (1675 200)(1400 200);
WIRE 16 -1 (1400 150)(1400 200);
WIRE 16 -1 (1400 200)(1125 200);
WIRE 16 -1 (1125 150)(1125 200);
WIRE 16 -1 (1125 200)(825 200);
WIRE 16 -1 (825 150)(825 200);
WIRE 16 -1 (825 200)(525 200);
WIRE 16 -1 (525 150)(525 200);
WIRE 16 -1 (525 200)(200 200);
WIRE 16 -1 (200 150)(200 200);
WIRE 16 -1 (200 200)(-75 200);
WIRE 16 -1 (-75 150)(-75 200);
WIRE 16 -1 (-75 200)(-375 200);
WIRE 16 -1 (-375 150)(-375 200);
WIRE 16 -1 (-375 200)(-675 200);
WIRE 16 -1 (-675 150)(-675 200);
WIRE 16 -1 (-675 200)(-950 200);
WIRE 16 -1 (-950 150)(-950 200);
WIRE 16 -1 (-1225 200)(-950 200);
WIRE 16 -1 (-1225 150)(-1225 200);
WIRE 16 -1 (-1525 200)(-1225 200);
WIRE 16 -1 (-1525 150)(-1525 200);
WIRE 16 -1 (-1825 200)(-1525 200);
WIRE 16 -1 (-1825 150)(-1825 200);
WIRE 16 -1 (-1825 200)(-1825 250);
WIRE 16 -1 (2550 -50)(2550 -125);
WIRE 16 -1 (2550 -125)(2275 -125);
WIRE 16 -1 (2275 -50)(2275 -125);
WIRE 16 -1 (2275 -125)(1975 -125);
WIRE 16 -1 (1975 -50)(1975 -125);
WIRE 16 -1 (1975 -125)(1675 -125);
WIRE 16 -1 (1675 -50)(1675 -125);
WIRE 16 -1 (1675 -125)(1400 -125);
WIRE 16 -1 (1400 -50)(1400 -125);
WIRE 16 -1 (1400 -125)(1125 -125);
WIRE 16 -1 (1125 -50)(1125 -125);
WIRE 16 -1 (1125 -125)(825 -125);
WIRE 16 -1 (825 -50)(825 -125);
WIRE 16 -1 (825 -125)(525 -125);
WIRE 16 -1 (525 -50)(525 -125);
WIRE 16 -1 (525 -125)(200 -125);
WIRE 16 -1 (200 -50)(200 -125);
WIRE 16 -1 (200 -125)(-75 -125);
WIRE 16 -1 (-75 -50)(-75 -125);
WIRE 16 -1 (-75 -125)(-375 -125);
WIRE 16 -1 (-375 -50)(-375 -125);
WIRE 16 -1 (-375 -125)(-675 -125);
WIRE 16 -1 (-675 -50)(-675 -125);
WIRE 16 -1 (-675 -125)(-950 -125);
WIRE 16 -1 (-950 -50)(-950 -125);
WIRE 16 -1 (-1225 -125)(-950 -125);
WIRE 16 -1 (-1225 -50)(-1225 -125);
WIRE 16 -1 (-1225 -125)(-1525 -125);
WIRE 16 -1 (-1525 -50)(-1525 -125);
WIRE 16 -1 (-1525 -125)(-1825 -125);
WIRE 16 -1 (-1825 -50)(-1825 -125);
WIRE 16 -1 (-1825 -125)(-1825 -175);
WIRE 16 -1 (2525 -550)(2525 -500);
WIRE 16 -1 (2525 -500)(2250 -500);
WIRE 16 -1 (2250 -550)(2250 -500);
WIRE 16 -1 (2250 -500)(1950 -500);
WIRE 16 -1 (1950 -550)(1950 -500);
WIRE 16 -1 (1950 -500)(1650 -500);
WIRE 16 -1 (1650 -550)(1650 -500);
WIRE 16 -1 (1650 -500)(1375 -500);
WIRE 16 -1 (1375 -550)(1375 -500);
WIRE 16 -1 (1375 -500)(1100 -500);
WIRE 16 -1 (1100 -550)(1100 -500);
WIRE 16 -1 (1100 -500)(800 -500);
WIRE 16 -1 (800 -550)(800 -500);
WIRE 16 -1 (800 -500)(500 -500);
WIRE 16 -1 (500 -550)(500 -500);
WIRE 16 -1 (500 -500)(175 -500);
WIRE 16 -1 (175 -550)(175 -500);
WIRE 16 -1 (175 -500)(-100 -500);
WIRE 16 -1 (-100 -550)(-100 -500);
WIRE 16 -1 (-100 -500)(-400 -500);
WIRE 16 -1 (-400 -550)(-400 -500);
WIRE 16 -1 (-400 -500)(-700 -500);
WIRE 16 -1 (-700 -550)(-700 -500);
WIRE 16 -1 (-700 -500)(-975 -500);
WIRE 16 -1 (-975 -550)(-975 -500);
WIRE 16 -1 (-1250 -500)(-975 -500);
WIRE 16 -1 (-1250 -550)(-1250 -500);
WIRE 16 -1 (-1550 -500)(-1250 -500);
WIRE 16 -1 (-1550 -550)(-1550 -500);
WIRE 16 -1 (-1850 -500)(-1550 -500);
WIRE 16 -1 (-1850 -550)(-1850 -500);
WIRE 16 -1 (-1850 -500)(-1850 -450);
WIRE 16 -1 (2525 -750)(2525 -825);
WIRE 16 -1 (2525 -825)(2250 -825);
WIRE 16 -1 (2250 -750)(2250 -825);
WIRE 16 -1 (2250 -825)(1950 -825);
WIRE 16 -1 (1950 -750)(1950 -825);
WIRE 16 -1 (1950 -825)(1650 -825);
WIRE 16 -1 (1650 -750)(1650 -825);
WIRE 16 -1 (1650 -825)(1375 -825);
WIRE 16 -1 (1375 -750)(1375 -825);
WIRE 16 -1 (1375 -825)(1100 -825);
WIRE 16 -1 (1100 -750)(1100 -825);
WIRE 16 -1 (1100 -825)(800 -825);
WIRE 16 -1 (800 -750)(800 -825);
WIRE 16 -1 (800 -825)(500 -825);
WIRE 16 -1 (500 -750)(500 -825);
WIRE 16 -1 (500 -825)(175 -825);
WIRE 16 -1 (175 -750)(175 -825);
WIRE 16 -1 (175 -825)(-100 -825);
WIRE 16 -1 (-100 -750)(-100 -825);
WIRE 16 -1 (-100 -825)(-400 -825);
WIRE 16 -1 (-400 -750)(-400 -825);
WIRE 16 -1 (-400 -825)(-700 -825);
WIRE 16 -1 (-700 -750)(-700 -825);
WIRE 16 -1 (-700 -825)(-975 -825);
WIRE 16 -1 (-975 -750)(-975 -825);
WIRE 16 -1 (-1250 -825)(-975 -825);
WIRE 16 -1 (-1250 -750)(-1250 -825);
WIRE 16 -1 (-1250 -825)(-1550 -825);
WIRE 16 -1 (-1550 -750)(-1550 -825);
WIRE 16 -1 (-1550 -825)(-1850 -825);
WIRE 16 -1 (-1850 -750)(-1850 -825);
WIRE 16 -1 (-1850 -825)(-1850 -875);
WIRE 16 -1 (400 1500)(275 1500);
WIRE 16 -1 (400 1325)(400 1500);
WIRE 16 -1 (425 2100)(425 1950);
WIRE 16 -1 (425 1950)(300 1950);
WIRE 16 -1 (4975 -375)(4975 -275);
WIRE 16 -1 (4625 -275)(4975 -275);
WIRE 16 -1 (4625 -375)(4625 -275);
WIRE 16 -1 (4225 -275)(4625 -275);
WIRE 16 -1 (4225 -350)(4225 -275);
WIRE 16 -1 (3800 -275)(4225 -275);
WIRE 16 -1 (3800 -350)(3800 -275);
WIRE 16 -1 (3375 -275)(3800 -275);
WIRE 16 -1 (3375 -350)(3375 -275);
WIRE 16 -1 (3375 -275)(3375 -200);
WIRE 16 -1 (4975 -575)(4975 -700);
WIRE 16 -1 (4625 -700)(4975 -700);
WIRE 16 -1 (4625 -575)(4625 -700);
WIRE 16 -1 (4625 -700)(4225 -700);
WIRE 16 -1 (4225 -550)(4225 -700);
WIRE 16 -1 (4225 -700)(3800 -700);
WIRE 16 -1 (3800 -550)(3800 -700);
WIRE 16 -1 (3800 -700)(3375 -700);
WIRE 16 -1 (3375 -700)(3375 -550);
WIRE 16 -1 (3375 -700)(3375 -825);
WIRE 16 -1 (5475 2950)(5475 3025);
WIRE 16 -1 (5475 3025)(5075 3025);
WIRE 16 -1 (5075 2950)(5075 3025);
WIRE 16 -1 (5075 3025)(4725 3025);
WIRE 16 -1 (4725 2950)(4725 3025);
WIRE 16 -1 (4725 3025)(4325 3025);
WIRE 16 -1 (4325 2950)(4325 3025);
WIRE 16 -1 (4325 3025)(3975 3025);
WIRE 16 -1 (3975 2950)(3975 3025);
WIRE 16 -1 (3975 3025)(3625 3025);
WIRE 16 -1 (3625 2950)(3625 3025);
WIRE 16 -1 (3625 3025)(3225 3025);
WIRE 16 -1 (3225 2950)(3225 3025);
WIRE 16 -1 (2875 3025)(3225 3025);
WIRE 16 -1 (2875 3025)(2875 3075);
WIRE 16 -1 (2875 3025)(2875 2950);
WIRE 16 -1 (2875 2750)(2875 2600);
WIRE 16 -1 (2875 2600)(3225 2600);
WIRE 16 -1 (3225 2750)(3225 2600);
WIRE 16 -1 (3225 2600)(3625 2600);
WIRE 16 -1 (3625 2750)(3625 2600);
WIRE 16 -1 (3625 2600)(3975 2600);
WIRE 16 -1 (3975 2750)(3975 2600);
WIRE 16 -1 (3975 2600)(4325 2600);
WIRE 16 -1 (4325 2750)(4325 2600);
WIRE 16 -1 (4600 2600)(4325 2600);
WIRE 16 -1 (4600 2600)(4725 2600);
WIRE 16 -1 (4600 2525)(4600 2600);
WIRE 16 -1 (4725 2600)(5075 2600);
WIRE 16 -1 (4725 2750)(4725 2600);
WIRE 16 -1 (5075 2600)(5475 2600);
WIRE 16 -1 (5075 2750)(5075 2600);
WIRE 16 -1 (5475 2750)(5475 2600);
WIRE 16 682 (425 3350)(425 2325);
WIRE 16 682 (425 3350)(-1900 3350);
WIRE 16 682 (425 2325)(-1900 2325);
WIRE 16 682 (-1900 2325)(-1900 3350);
WIRE 16 2175 (5875 275)(5875 3400);
WIRE 16 2175 (5875 275)(2700 275);
WIRE 16 2175 (2700 3400)(5875 3400);
WIRE 16 2175 (2700 275)(2700 3400);
WIRE 16 682 (3100 25)(5850 25);
WIRE 16 682 (3100 -1000)(3100 25);
WIRE 16 682 (5850 25)(5850 -1000);
WIRE 16 682 (5850 -1000)(3100 -1000);
WIRE 16 2175 (2775 2250)(5850 2250);
WIRE 16 -1 (-250 1800)(-250 1950);
WIRE 16 -1 (0 1950)(-250 1950);
WIRE 16 -1 (-250 1950)(-350 1950);
WIRE 16 -1 (-350 1950)(-350 1800);
WIRE 16 -1 (-350 1800)(-750 1800);
WIRE 16 -1 (-750 1800)(-750 1925);
WIRE 16 -1 (-750 1925)(-1475 1925);
FORCEPROP 2 LAST SIG_NAME VSENSE_PVDDQ_ABC_P
J 0
(-1480 1940);
DISPLAY 0.617021 (-1480 1940);
PAINT ORANGE (-1480 1940);
WIRE 16 -1 (-25 1500)(-250 1500);
WIRE 16 -1 (-250 1600)(-250 1500);
WIRE 16 -1 (-250 1500)(-350 1500);
WIRE 16 -1 (-350 1725)(-350 1500);
WIRE 16 -1 (-750 1725)(-350 1725);
WIRE 16 -1 (-750 1675)(-750 1725);
WIRE 16 -1 (-1475 1675)(-750 1675);
FORCEPROP 2 LAST SIG_NAME VSENSE_PVDDQ_ABC_N
J 0
(-1485 1685);
DISPLAY 0.617021 (-1485 1685);
PAINT ORANGE (-1485 1685);
DOT 1 (5075 3025);
DOT 1 (5075 2600);
DOT 1 (4725 3025);
DOT 1 (4725 2600);
DOT 1 (4600 2600);
DOT 1 (4325 3025);
DOT 1 (4325 2600);
DOT 1 (4625 1475);
DOT 1 (4350 1900);
DOT 1 (4350 1475);
DOT 1 (3975 3025);
DOT 1 (3975 2600);
DOT 1 (3625 3025);
DOT 1 (3625 2600);
DOT 1 (3225 3025);
DOT 1 (3225 2600);
DOT 1 (2875 3025);
DOT 1 (4000 1900);
DOT 1 (3650 1900);
DOT 1 (4000 1475);
DOT 1 (3650 1475);
DOT 1 (3250 1900);
DOT 1 (3250 1475);
DOT 1 (3275 1175);
DOT 1 (3575 750);
DOT 1 (3275 750);
DOT 1 (2900 1900);
DOT 1 (2925 1175);
DOT 1 (2275 200);
DOT 1 (150 2600);
DOT 1 (1975 200);
DOT 1 (1675 200);
DOT 1 (1400 200);
DOT 1 (1125 200);
DOT 1 (825 200);
DOT 1 (525 200);
DOT 1 (200 900);
DOT 1 (200 200);
DOT 1 (4625 -275);
DOT 1 (4625 -700);
DOT 1 (4225 -275);
DOT 1 (4225 -700);
DOT 1 (3800 -275);
DOT 1 (3800 -700);
DOT 1 (3375 -275);
DOT 1 (3375 -700);
DOT 1 (2275 -125);
DOT 1 (2250 -500);
DOT 1 (2250 -825);
DOT 1 (1975 -125);
DOT 1 (1675 -125);
DOT 1 (1950 -500);
DOT 1 (1650 -500);
DOT 1 (1950 -825);
DOT 1 (1650 -825);
DOT 1 (1400 -125);
DOT 1 (1125 -125);
DOT 1 (1375 -500);
DOT 1 (1100 -500);
DOT 1 (1375 -825);
DOT 1 (1100 -825);
DOT 1 (825 -125);
DOT 1 (800 -500);
DOT 1 (800 -825);
DOT 1 (525 -125);
DOT 1 (200 -125);
DOT 1 (500 -500);
DOT 1 (175 -500);
DOT 1 (500 -825);
DOT 1 (175 -825);
DOT 1 (-200 3025);
DOT 1 (-200 2600);
DOT 1 (-550 3025);
DOT 1 (-550 2600);
DOT 1 (-900 3025);
DOT 1 (-1300 2600);
DOT 1 (-1650 3025);
DOT 1 (-250 1950);
DOT 1 (-250 1500);
DOT 1 (-75 200);
DOT 1 (-375 200);
DOT 1 (-675 200);
DOT 1 (-950 200);
DOT 1 (-1225 200);
DOT 1 (-1525 200);
DOT 1 (-1825 200);
DOT 1 (-75 -125);
DOT 1 (-375 -125);
DOT 1 (-100 -500);
DOT 1 (-400 -500);
DOT 1 (-100 -825);
DOT 1 (-400 -825);
DOT 1 (-675 -125);
DOT 1 (-950 -125);
DOT 1 (-700 -500);
DOT 1 (-975 -500);
DOT 1 (-700 -825);
DOT 1 (-975 -825);
DOT 1 (-1225 -125);
DOT 1 (-1250 -500);
DOT 1 (-1250 -825);
DOT 1 (-1525 -125);
DOT 1 (-1825 -125);
DOT 1 (-1550 -500);
DOT 1 (-1850 -500);
DOT 1 (-1550 -825);
DOT 1 (-1850 -825);
FORCENOTE
BOTTOM SIDE: 805
(-1600 3050) 0;
DISPLAY LEFT (-1600 3050);
DISPLAY 0.638298 (-1600 3050);
PAINT PURPLE (-1600 3050);
FORCENOTE
CAPS TO BE PLACED BETWEEN DIMMS
(2770 3280) 0;
DISPLAY LEFT (2770 3280);
DISPLAY 1.021277 (2770 3280);
PAINT PURPLE (2770 3280);
FORCENOTE
PLACE NEAR VR OUTPUT INDUCTORS
(3575 -975) 0;
DISPLAY LEFT (3575 -975);
DISPLAY 1.021277 (3575 -975);
PAINT PURPLE (3575 -975);
FORCENOTE
CAD NOTE:
(3550 -900) 0;
DISPLAY LEFT (3550 -900);
DISPLAY 1.021277 (3550 -900);
PAINT PURPLE (3550 -900);
FORCENOTE
ROOM = VDDQ_ABC_PWR_VR
(-1890 -1310) 0;
DISPLAY LEFT (-1890 -1310);
DISPLAY 2.446809 (-1890 -1310);
PAINT PURPLE (-1890 -1310);
FORCENOTE
INPUT FILTER
(-530 605) 0;
DISPLAY LEFT (-530 605);
PAINT PURPLE (-530 605);
FORCENOTE
PVDDQ CPU CAVITY CAPS
(-775 2375) 0;
DISPLAY LEFT (-775 2375);
DISPLAY 1.021277 (-775 2375);
PAINT PURPLE (-775 2375);
FORCENOTE
ROOM=VDDQ_ABC_CPU0
(-1750 2375) 0;
DISPLAY LEFT (-1750 2375);
DISPLAY 1.021277 (-1750 2375);
PAINT PURPLE (-1750 2375);
FORCENOTE
10MIL WIDTH
(-695 1655) 0;
DISPLAY LEFT (-695 1655);
DISPLAY 0.808511 (-695 1655);
PAINT PURPLE (-695 1655);
FORCENOTE
5MIL SPACING
(-720 1605) 0;
DISPLAY LEFT (-720 1605);
DISPLAY 0.808511 (-720 1605);
PAINT PURPLE (-720 1605);
FORCENOTE
ROUT AS DIFF PAIR
(-770 1755) 0;
DISPLAY LEFT (-770 1755);
DISPLAY 0.808511 (-770 1755);
PAINT PURPLE (-770 1755);
FORCENOTE
PVDDQ_ABC VOLTAGE SENSE
(-1445 1405) 0;
DISPLAY LEFT (-1445 1405);
PAINT PURPLE (-1445 1405);
FORCENOTE
TOP SIDE: 603
(-775 3050) 0;
DISPLAY LEFT (-775 3050);
DISPLAY 0.638298 (-775 3050);
PAINT PURPLE (-775 3050);
QUIT
